FILE_TYPE = MACRO_DRAWING;
SET COLOR_WIRE YELLOW;
SET COLOR_PROP MONO;
SET COLOR_DOT WHITE;
SET COLOR_ARC YELLOW;
SET COLOR_BODY GREEN;
SET COLOR_NOTE MONO;
SET PROP_DISPLAY VALUE;
SET PAGE_NUMBER P77;
FORCEADD OFFPAGE..3
(1600 5100);
FORCEPROP 2 LAST $XR1 78 
J 0
(1904 5100);
DISPLAY 0.638298 (1904 5100);
PAINT MONO (1904 5100);
FORCEPROP 2 LAST $XR0 57 
J 0
(1814 5100);
DISPLAY 0.638298 (1814 5100);
PAINT MONO (1814 5100);
FORCEPROP 2 LAST CDS_LIB mstr_standard
J 0
(1600 5100);
DISPLAY 0.787234 (1600 5100);
PAINT MONO (1600 5100);
DISPLAY INVISIBLE (1600 5100);
FORCEPROP 1 LAST OFFPAGE TRUE
J 0
(1925 4975);
DISPLAY 0.936170 (1925 4975);
PAINT GREEN (1925 4975);
DISPLAY INVISIBLE (1925 4975);
FORCEPROP 1 LAST COMMENT_BODY TRUE
J 0
(1550 5000);
DISPLAY 0.936170 (1550 5000);
PAINT GREEN (1550 5000);
DISPLAY INVISIBLE (1550 5000);
FORCEPROP 2 LAST PATH I1
J 0
(1800 5175);
DISPLAY 0.787234 (1800 5175);
PAINT MONO (1800 5175);
DISPLAY INVISIBLE (1800 5175);
FORCEADD TAP..6
R 2
(700 4750);
FORCEPROP 3 LASTPIN (650 4750) SIG_NAME M_G_DQS_DP<14>
J 0
(660 4760);
DISPLAY 0.659574 (660 4760);
PAINT MONO (660 4760);
DISPLAY INVISIBLE (660 4760);
FORCEPROP 1 LASTPIN (650 4750) BN 14
J 2
(700 4760);
DISPLAY 0.617021 (700 4760);
PAINT PINK (700 4760);
FORCEPROP 2 LAST CDS_LIB mstr_standard
J 0
(700 4750);
DISPLAY 0.787234 (700 4750);
PAINT MONO (700 4750);
DISPLAY INVISIBLE (700 4750);
FORCEPROP 1 LAST BODY_TYPE PLUMBING
J 2
(700 4700);
DISPLAY 1.234043 (700 4700);
PAINT GREEN (700 4700);
DISPLAY INVISIBLE (700 4700);
FORCEPROP 1 LAST HDL_TAP TRUE
J 2
(375 4625);
DISPLAY 1.234043 (375 4625);
PAINT GREEN (375 4625);
DISPLAY INVISIBLE (375 4625);
FORCEPROP 1 LAST PATH I10
J 2
(700 4750);
DISPLAY 0.936170 (700 4750);
PAINT GREEN (700 4750);
DISPLAY INVISIBLE (700 4750);
FORCEADD TAP..6
R 2
(-1625 1775);
FORCEPROP 3 LASTPIN (-1675 1775) SIG_NAME M_G_DQ<11>
J 0
(-1665 1785);
DISPLAY 0.659574 (-1665 1785);
PAINT MONO (-1665 1785);
DISPLAY INVISIBLE (-1665 1785);
FORCEPROP 1 LASTPIN (-1675 1775) BN 11
J 2
(-1625 1785);
DISPLAY 0.617021 (-1625 1785);
PAINT PINK (-1625 1785);
FORCEPROP 2 LAST CDS_LIB mstr_standard
J 2
(-1625 1775);
DISPLAY 0.787234 (-1625 1775);
PAINT MONO (-1625 1775);
DISPLAY INVISIBLE (-1625 1775);
FORCEPROP 1 LAST BODY_TYPE PLUMBING
J 2
(-1625 1725);
DISPLAY 1.234043 (-1625 1725);
PAINT GREEN (-1625 1725);
DISPLAY INVISIBLE (-1625 1725);
FORCEPROP 1 LAST HDL_TAP TRUE
J 2
(-1950 1650);
DISPLAY 1.234043 (-1950 1650);
PAINT GREEN (-1950 1650);
DISPLAY INVISIBLE (-1950 1650);
FORCEPROP 1 LAST PATH I100
J 2
(-1625 1775);
DISPLAY 0.936170 (-1625 1775);
PAINT GREEN (-1625 1775);
DISPLAY INVISIBLE (-1625 1775);
FORCEADD TAP..6
R 2
(-1625 1725);
FORCEPROP 3 LASTPIN (-1675 1725) SIG_NAME M_G_DQ<8>
J 0
(-1665 1735);
DISPLAY 0.659574 (-1665 1735);
PAINT MONO (-1665 1735);
DISPLAY INVISIBLE (-1665 1735);
FORCEPROP 1 LASTPIN (-1675 1725) BN 8
J 2
(-1625 1735);
DISPLAY 0.617021 (-1625 1735);
PAINT PINK (-1625 1735);
FORCEPROP 2 LAST CDS_LIB mstr_standard
J 2
(-1625 1725);
DISPLAY 0.787234 (-1625 1725);
PAINT MONO (-1625 1725);
DISPLAY INVISIBLE (-1625 1725);
FORCEPROP 1 LAST BODY_TYPE PLUMBING
J 2
(-1625 1675);
DISPLAY 1.234043 (-1625 1675);
PAINT GREEN (-1625 1675);
DISPLAY INVISIBLE (-1625 1675);
FORCEPROP 1 LAST HDL_TAP TRUE
J 2
(-1950 1600);
DISPLAY 1.234043 (-1950 1600);
PAINT GREEN (-1950 1600);
DISPLAY INVISIBLE (-1950 1600);
FORCEPROP 1 LAST PATH I101
J 2
(-1625 1725);
DISPLAY 0.936170 (-1625 1725);
PAINT GREEN (-1625 1725);
DISPLAY INVISIBLE (-1625 1725);
FORCEADD TAP..6
R 2
(-1625 1675);
FORCEPROP 3 LASTPIN (-1675 1675) SIG_NAME M_G_DQ<9>
J 0
(-1665 1685);
DISPLAY 0.659574 (-1665 1685);
PAINT MONO (-1665 1685);
DISPLAY INVISIBLE (-1665 1685);
FORCEPROP 1 LASTPIN (-1675 1675) BN 9
J 2
(-1625 1685);
DISPLAY 0.617021 (-1625 1685);
PAINT PINK (-1625 1685);
FORCEPROP 2 LAST CDS_LIB mstr_standard
J 2
(-1625 1675);
DISPLAY 0.787234 (-1625 1675);
PAINT MONO (-1625 1675);
DISPLAY INVISIBLE (-1625 1675);
FORCEPROP 1 LAST BODY_TYPE PLUMBING
J 2
(-1625 1625);
DISPLAY 1.234043 (-1625 1625);
PAINT GREEN (-1625 1625);
DISPLAY INVISIBLE (-1625 1625);
FORCEPROP 1 LAST HDL_TAP TRUE
J 2
(-1950 1550);
DISPLAY 1.234043 (-1950 1550);
PAINT GREEN (-1950 1550);
DISPLAY INVISIBLE (-1950 1550);
FORCEPROP 1 LAST PATH I102
J 2
(-1625 1675);
DISPLAY 0.936170 (-1625 1675);
PAINT GREEN (-1625 1675);
DISPLAY INVISIBLE (-1625 1675);
FORCEADD TAP..6
R 2
(-1625 1575);
FORCEPROP 3 LASTPIN (-1675 1575) SIG_NAME M_G_DQ<7>
J 0
(-1665 1585);
DISPLAY 0.659574 (-1665 1585);
PAINT MONO (-1665 1585);
DISPLAY INVISIBLE (-1665 1585);
FORCEPROP 1 LASTPIN (-1675 1575) BN 7
J 2
(-1625 1585);
DISPLAY 0.617021 (-1625 1585);
PAINT PINK (-1625 1585);
FORCEPROP 2 LAST CDS_LIB mstr_standard
J 2
(-1625 1575);
DISPLAY 0.787234 (-1625 1575);
PAINT MONO (-1625 1575);
DISPLAY INVISIBLE (-1625 1575);
FORCEPROP 1 LAST BODY_TYPE PLUMBING
J 2
(-1625 1525);
DISPLAY 1.234043 (-1625 1525);
PAINT GREEN (-1625 1525);
DISPLAY INVISIBLE (-1625 1525);
FORCEPROP 1 LAST HDL_TAP TRUE
J 2
(-1950 1450);
DISPLAY 1.234043 (-1950 1450);
PAINT GREEN (-1950 1450);
DISPLAY INVISIBLE (-1950 1450);
FORCEPROP 1 LAST PATH I103
J 2
(-1625 1575);
DISPLAY 0.936170 (-1625 1575);
PAINT GREEN (-1625 1575);
DISPLAY INVISIBLE (-1625 1575);
FORCEADD TAP..6
R 2
(-1625 1625);
FORCEPROP 3 LASTPIN (-1675 1625) SIG_NAME M_G_DQ<6>
J 0
(-1665 1635);
DISPLAY 0.659574 (-1665 1635);
PAINT MONO (-1665 1635);
DISPLAY INVISIBLE (-1665 1635);
FORCEPROP 1 LASTPIN (-1675 1625) BN 6
J 2
(-1625 1635);
DISPLAY 0.617021 (-1625 1635);
PAINT PINK (-1625 1635);
FORCEPROP 2 LAST CDS_LIB mstr_standard
J 2
(-1625 1625);
DISPLAY 0.787234 (-1625 1625);
PAINT MONO (-1625 1625);
DISPLAY INVISIBLE (-1625 1625);
FORCEPROP 1 LAST BODY_TYPE PLUMBING
J 2
(-1625 1575);
DISPLAY 1.234043 (-1625 1575);
PAINT GREEN (-1625 1575);
DISPLAY INVISIBLE (-1625 1575);
FORCEPROP 1 LAST HDL_TAP TRUE
J 2
(-1950 1500);
DISPLAY 1.234043 (-1950 1500);
PAINT GREEN (-1950 1500);
DISPLAY INVISIBLE (-1950 1500);
FORCEPROP 1 LAST PATH I104
J 2
(-1625 1625);
DISPLAY 0.936170 (-1625 1625);
PAINT GREEN (-1625 1625);
DISPLAY INVISIBLE (-1625 1625);
FORCEADD TAP..6
R 2
(-1625 1425);
FORCEPROP 3 LASTPIN (-1675 1425) SIG_NAME M_G_DQ<2>
J 0
(-1665 1435);
DISPLAY 0.659574 (-1665 1435);
PAINT MONO (-1665 1435);
DISPLAY INVISIBLE (-1665 1435);
FORCEPROP 1 LASTPIN (-1675 1425) BN 2
J 2
(-1625 1435);
DISPLAY 0.617021 (-1625 1435);
PAINT PINK (-1625 1435);
FORCEPROP 2 LAST CDS_LIB mstr_standard
J 2
(-1625 1425);
DISPLAY 0.787234 (-1625 1425);
PAINT MONO (-1625 1425);
DISPLAY INVISIBLE (-1625 1425);
FORCEPROP 1 LAST BODY_TYPE PLUMBING
J 2
(-1625 1375);
DISPLAY 1.234043 (-1625 1375);
PAINT GREEN (-1625 1375);
DISPLAY INVISIBLE (-1625 1375);
FORCEPROP 1 LAST HDL_TAP TRUE
J 2
(-1950 1300);
DISPLAY 1.234043 (-1950 1300);
PAINT GREEN (-1950 1300);
DISPLAY INVISIBLE (-1950 1300);
FORCEPROP 1 LAST PATH I105
J 2
(-1625 1425);
DISPLAY 0.936170 (-1625 1425);
PAINT GREEN (-1625 1425);
DISPLAY INVISIBLE (-1625 1425);
FORCEADD TAP..6
R 2
(-1625 1475);
FORCEPROP 3 LASTPIN (-1675 1475) SIG_NAME M_G_DQ<5>
J 0
(-1665 1485);
DISPLAY 0.659574 (-1665 1485);
PAINT MONO (-1665 1485);
DISPLAY INVISIBLE (-1665 1485);
FORCEPROP 1 LASTPIN (-1675 1475) BN 5
J 2
(-1625 1485);
DISPLAY 0.617021 (-1625 1485);
PAINT PINK (-1625 1485);
FORCEPROP 2 LAST CDS_LIB mstr_standard
J 2
(-1625 1475);
DISPLAY 0.787234 (-1625 1475);
PAINT MONO (-1625 1475);
DISPLAY INVISIBLE (-1625 1475);
FORCEPROP 1 LAST BODY_TYPE PLUMBING
J 2
(-1625 1425);
DISPLAY 1.234043 (-1625 1425);
PAINT GREEN (-1625 1425);
DISPLAY INVISIBLE (-1625 1425);
FORCEPROP 1 LAST HDL_TAP TRUE
J 2
(-1950 1350);
DISPLAY 1.234043 (-1950 1350);
PAINT GREEN (-1950 1350);
DISPLAY INVISIBLE (-1950 1350);
FORCEPROP 1 LAST PATH I106
J 2
(-1625 1475);
DISPLAY 0.936170 (-1625 1475);
PAINT GREEN (-1625 1475);
DISPLAY INVISIBLE (-1625 1475);
FORCEADD TAP..6
R 2
(-1625 1525);
FORCEPROP 3 LASTPIN (-1675 1525) SIG_NAME M_G_DQ<4>
J 0
(-1665 1535);
DISPLAY 0.659574 (-1665 1535);
PAINT MONO (-1665 1535);
DISPLAY INVISIBLE (-1665 1535);
FORCEPROP 1 LASTPIN (-1675 1525) BN 4
J 2
(-1625 1535);
DISPLAY 0.617021 (-1625 1535);
PAINT PINK (-1625 1535);
FORCEPROP 2 LAST CDS_LIB mstr_standard
J 2
(-1625 1525);
DISPLAY 0.787234 (-1625 1525);
PAINT MONO (-1625 1525);
DISPLAY INVISIBLE (-1625 1525);
FORCEPROP 1 LAST BODY_TYPE PLUMBING
J 2
(-1625 1475);
DISPLAY 1.234043 (-1625 1475);
PAINT GREEN (-1625 1475);
DISPLAY INVISIBLE (-1625 1475);
FORCEPROP 1 LAST HDL_TAP TRUE
J 2
(-1950 1400);
DISPLAY 1.234043 (-1950 1400);
PAINT GREEN (-1950 1400);
DISPLAY INVISIBLE (-1950 1400);
FORCEPROP 1 LAST PATH I107
J 2
(-1625 1525);
DISPLAY 0.936170 (-1625 1525);
PAINT GREEN (-1625 1525);
DISPLAY INVISIBLE (-1625 1525);
FORCEADD TAP..6
R 2
(-1625 1325);
FORCEPROP 3 LASTPIN (-1675 1325) SIG_NAME M_G_DQ<0>
J 0
(-1665 1335);
DISPLAY 0.659574 (-1665 1335);
PAINT MONO (-1665 1335);
DISPLAY INVISIBLE (-1665 1335);
FORCEPROP 1 LASTPIN (-1675 1325) BN 0
J 2
(-1625 1335);
DISPLAY 0.617021 (-1625 1335);
PAINT PINK (-1625 1335);
FORCEPROP 2 LAST CDS_LIB mstr_standard
J 2
(-1625 1325);
DISPLAY 0.787234 (-1625 1325);
PAINT MONO (-1625 1325);
DISPLAY INVISIBLE (-1625 1325);
FORCEPROP 1 LAST BODY_TYPE PLUMBING
J 2
(-1625 1275);
DISPLAY 1.234043 (-1625 1275);
PAINT GREEN (-1625 1275);
DISPLAY INVISIBLE (-1625 1275);
FORCEPROP 1 LAST HDL_TAP TRUE
J 2
(-1950 1200);
DISPLAY 1.234043 (-1950 1200);
PAINT GREEN (-1950 1200);
DISPLAY INVISIBLE (-1950 1200);
FORCEPROP 1 LAST PATH I108
J 2
(-1625 1325);
DISPLAY 0.936170 (-1625 1325);
PAINT GREEN (-1625 1325);
DISPLAY INVISIBLE (-1625 1325);
FORCEADD TAP..6
R 2
(-1625 1275);
FORCEPROP 3 LASTPIN (-1675 1275) SIG_NAME M_G_DQ<1>
J 0
(-1665 1285);
DISPLAY 0.659574 (-1665 1285);
PAINT MONO (-1665 1285);
DISPLAY INVISIBLE (-1665 1285);
FORCEPROP 1 LASTPIN (-1675 1275) BN 1
J 2
(-1625 1285);
DISPLAY 0.617021 (-1625 1285);
PAINT PINK (-1625 1285);
FORCEPROP 2 LAST CDS_LIB mstr_standard
J 2
(-1625 1275);
DISPLAY 0.787234 (-1625 1275);
PAINT MONO (-1625 1275);
DISPLAY INVISIBLE (-1625 1275);
FORCEPROP 1 LAST BODY_TYPE PLUMBING
J 2
(-1625 1225);
DISPLAY 1.234043 (-1625 1225);
PAINT GREEN (-1625 1225);
DISPLAY INVISIBLE (-1625 1225);
FORCEPROP 1 LAST HDL_TAP TRUE
J 2
(-1950 1150);
DISPLAY 1.234043 (-1950 1150);
PAINT GREEN (-1950 1150);
DISPLAY INVISIBLE (-1950 1150);
FORCEPROP 1 LAST PATH I109
J 2
(-1625 1275);
DISPLAY 0.936170 (-1625 1275);
PAINT GREEN (-1625 1275);
DISPLAY INVISIBLE (-1625 1275);
FORCEADD TAP..6
R 2
(700 4850);
FORCEPROP 3 LASTPIN (650 4850) SIG_NAME M_G_DQS_DP<15>
J 0
(660 4860);
DISPLAY 0.659574 (660 4860);
PAINT MONO (660 4860);
DISPLAY INVISIBLE (660 4860);
FORCEPROP 1 LASTPIN (650 4850) BN 15
J 2
(700 4860);
DISPLAY 0.617021 (700 4860);
PAINT PINK (700 4860);
FORCEPROP 2 LAST CDS_LIB mstr_standard
J 0
(700 4850);
DISPLAY 0.787234 (700 4850);
PAINT MONO (700 4850);
DISPLAY INVISIBLE (700 4850);
FORCEPROP 1 LAST BODY_TYPE PLUMBING
J 2
(700 4800);
DISPLAY 1.234043 (700 4800);
PAINT GREEN (700 4800);
DISPLAY INVISIBLE (700 4800);
FORCEPROP 1 LAST HDL_TAP TRUE
J 2
(375 4725);
DISPLAY 1.234043 (375 4725);
PAINT GREEN (375 4725);
DISPLAY INVISIBLE (375 4725);
FORCEPROP 1 LAST PATH I11
J 2
(700 4850);
DISPLAY 0.936170 (700 4850);
PAINT GREEN (700 4850);
DISPLAY INVISIBLE (700 4850);
FORCEADD TAP..6
R 2
(-1625 1375);
FORCEPROP 3 LASTPIN (-1675 1375) SIG_NAME M_G_DQ<3>
J 0
(-1665 1385);
DISPLAY 0.659574 (-1665 1385);
PAINT MONO (-1665 1385);
DISPLAY INVISIBLE (-1665 1385);
FORCEPROP 1 LASTPIN (-1675 1375) BN 3
J 2
(-1625 1385);
DISPLAY 0.617021 (-1625 1385);
PAINT PINK (-1625 1385);
FORCEPROP 2 LAST CDS_LIB mstr_standard
J 2
(-1625 1375);
DISPLAY 0.787234 (-1625 1375);
PAINT MONO (-1625 1375);
DISPLAY INVISIBLE (-1625 1375);
FORCEPROP 1 LAST BODY_TYPE PLUMBING
J 2
(-1625 1325);
DISPLAY 1.234043 (-1625 1325);
PAINT GREEN (-1625 1325);
DISPLAY INVISIBLE (-1625 1325);
FORCEPROP 1 LAST HDL_TAP TRUE
J 2
(-1950 1250);
DISPLAY 1.234043 (-1950 1250);
PAINT GREEN (-1950 1250);
DISPLAY INVISIBLE (-1950 1250);
FORCEPROP 1 LAST PATH I110
J 2
(-1625 1375);
DISPLAY 0.936170 (-1625 1375);
PAINT GREEN (-1625 1375);
DISPLAY INVISIBLE (-1625 1375);
FORCEADD SCONN288_H44441004..1
(-2375 2775);
FORCEPROP 2 LASTPIN (-1875 1325) $PN 150
J 0
(-1865 1335);
DISPLAY 0.617021 (-1865 1335);
PAINT ORANGE (-1865 1335);
FORCEPROP 1 LAST LOCATION J1G1
J 0
(-2825 4675);
DISPLAY 0.617021 (-2825 4675);
PAINT AQUA (-2825 4675);
FORCEPROP 1 LAST PART_NUMBER H44441-004
J 0
(-2825 775);
DISPLAY 0.617021 (-2825 775);
PAINT BLUE (-2825 775);
FORCEPROP 2 LASTPIN (-2875 1275) $PN 146
J 2
(-2885 1285);
DISPLAY 0.617021 (-2885 1285);
PAINT ORANGE (-2885 1285);
FORCEPROP 2 LASTPIN (-2875 1625) $PN 284
J 2
(-2885 1635);
DISPLAY 0.617021 (-2885 1635);
PAINT ORANGE (-2885 1635);
FORCEPROP 2 LASTPIN (-2875 1425) $PN 285
J 2
(-2885 1435);
DISPLAY 0.617021 (-2885 1435);
PAINT ORANGE (-2885 1435);
FORCEPROP 2 LASTPIN (-2875 1375) $PN 141
J 2
(-2885 1385);
DISPLAY 0.617021 (-2885 1385);
PAINT ORANGE (-2885 1385);
FORCEPROP 2 LASTPIN (-2875 975) $PN 230
J 2
(-2885 985);
DISPLAY 0.617021 (-2885 985);
PAINT ORANGE (-2885 985);
FORCEPROP 2 LASTPIN (-2875 1575) $PN 238
J 2
(-2885 1585);
DISPLAY 0.617021 (-2885 1585);
PAINT ORANGE (-2885 1585);
FORCEPROP 2 LASTPIN (-2875 1525) $PN 140
J 2
(-2885 1535);
DISPLAY 0.617021 (-2885 1535);
PAINT ORANGE (-2885 1535);
FORCEPROP 2 LASTPIN (-2875 1475) $PN 139
J 2
(-2885 1485);
DISPLAY 0.617021 (-2885 1485);
PAINT ORANGE (-2885 1485);
FORCEPROP 2 LASTPIN (-2875 2925) $PN 237
J 2
(-2885 2935);
DISPLAY 0.617021 (-2885 2935);
PAINT ORANGE (-2885 2935);
FORCEPROP 2 LASTPIN (-2875 2875) $PN 93
J 2
(-2885 2885);
DISPLAY 0.617021 (-2885 2885);
PAINT ORANGE (-2885 2885);
FORCEPROP 2 LASTPIN (-2875 2825) $PN 89
J 2
(-2885 2835);
DISPLAY 0.617021 (-2885 2835);
PAINT ORANGE (-2885 2835);
FORCEPROP 2 LASTPIN (-2875 2775) $PN 84
J 2
(-2885 2785);
DISPLAY 0.617021 (-2885 2785);
PAINT ORANGE (-2885 2785);
FORCEPROP 2 LASTPIN (-2875 1175) $PN 144
J 2
(-2885 1185);
DISPLAY 0.617021 (-2885 1185);
PAINT ORANGE (-2885 1185);
FORCEPROP 2 LASTPIN (-2875 1125) $PN 227
J 2
(-2885 1135);
DISPLAY 0.617021 (-2885 1135);
PAINT ORANGE (-2885 1135);
FORCEPROP 2 LASTPIN (-2875 1075) $PN 205
J 2
(-2885 1085);
DISPLAY 0.617021 (-2885 1085);
PAINT ORANGE (-2885 1085);
FORCEPROP 2 LASTPIN (-2875 1875) $PN 58
J 2
(-2885 1885);
DISPLAY 0.617021 (-2885 1885);
PAINT ORANGE (-2885 1885);
FORCEPROP 2 LASTPIN (-2875 1925) $PN 222
J 2
(-2885 1935);
DISPLAY 0.617021 (-2885 1935);
PAINT ORANGE (-2885 1935);
FORCEPROP 2 LASTPIN (-2875 2525) $PN 91
J 2
(-2885 2535);
DISPLAY 0.617021 (-2885 2535);
PAINT ORANGE (-2885 2535);
FORCEPROP 2 LASTPIN (-2875 2475) $PN 87
J 2
(-2885 2485);
DISPLAY 0.617021 (-2885 2485);
PAINT ORANGE (-2885 2485);
FORCEPROP 2 LASTPIN (-2875 1825) $PN 78
J 2
(-2885 1835);
DISPLAY 0.617021 (-2885 1835);
PAINT ORANGE (-2885 1835);
FORCEPROP 2 LASTPIN (-1875 4425) $PN 280
J 0
(-1865 4435);
DISPLAY 0.617021 (-1865 4435);
PAINT ORANGE (-1865 4435);
FORCEPROP 2 LASTPIN (-1875 4375) $PN 135
J 0
(-1865 4385);
DISPLAY 0.617021 (-1865 4385);
PAINT ORANGE (-1865 4385);
FORCEPROP 2 LASTPIN (-1875 4325) $PN 273
J 0
(-1865 4335);
DISPLAY 0.617021 (-1865 4335);
PAINT ORANGE (-1865 4335);
FORCEPROP 2 LASTPIN (-1875 4225) $PN 282
J 0
(-1865 4235);
DISPLAY 0.617021 (-1865 4235);
PAINT ORANGE (-1865 4235);
FORCEPROP 2 LASTPIN (-1875 4175) $PN 137
J 0
(-1865 4185);
DISPLAY 0.617021 (-1865 4185);
PAINT ORANGE (-1865 4185);
FORCEPROP 2 LASTPIN (-1875 4125) $PN 275
J 0
(-1865 4135);
DISPLAY 0.617021 (-1865 4135);
PAINT ORANGE (-1865 4135);
FORCEPROP 2 LASTPIN (-1875 4075) $PN 130
J 0
(-1865 4085);
DISPLAY 0.617021 (-1865 4085);
PAINT ORANGE (-1865 4085);
FORCEPROP 2 LASTPIN (-1875 4025) $PN 269
J 0
(-1865 4035);
DISPLAY 0.617021 (-1865 4035);
PAINT ORANGE (-1865 4035);
FORCEPROP 2 LASTPIN (-1875 3975) $PN 124
J 0
(-1865 3985);
DISPLAY 0.617021 (-1865 3985);
PAINT ORANGE (-1865 3985);
FORCEPROP 2 LASTPIN (-1875 3925) $PN 262
J 0
(-1865 3935);
DISPLAY 0.617021 (-1865 3935);
PAINT ORANGE (-1865 3935);
FORCEPROP 2 LASTPIN (-1875 3875) $PN 117
J 0
(-1865 3885);
DISPLAY 0.617021 (-1865 3885);
PAINT ORANGE (-1865 3885);
FORCEPROP 2 LASTPIN (-1875 3825) $PN 271
J 0
(-1865 3835);
DISPLAY 0.617021 (-1865 3835);
PAINT ORANGE (-1865 3835);
FORCEPROP 2 LASTPIN (-1875 3775) $PN 126
J 0
(-1865 3785);
DISPLAY 0.617021 (-1865 3785);
PAINT ORANGE (-1865 3785);
FORCEPROP 2 LASTPIN (-1875 3725) $PN 264
J 0
(-1865 3735);
DISPLAY 0.617021 (-1865 3735);
PAINT ORANGE (-1865 3735);
FORCEPROP 2 LASTPIN (-1875 3675) $PN 119
J 0
(-1865 3685);
DISPLAY 0.617021 (-1865 3685);
PAINT ORANGE (-1865 3685);
FORCEPROP 2 LASTPIN (-1875 3625) $PN 258
J 0
(-1865 3635);
DISPLAY 0.617021 (-1865 3635);
PAINT ORANGE (-1865 3635);
FORCEPROP 2 LASTPIN (-1875 3575) $PN 113
J 0
(-1865 3585);
DISPLAY 0.617021 (-1865 3585);
PAINT ORANGE (-1865 3585);
FORCEPROP 2 LASTPIN (-1875 3525) $PN 251
J 0
(-1865 3535);
DISPLAY 0.617021 (-1865 3535);
PAINT ORANGE (-1865 3535);
FORCEPROP 2 LASTPIN (-1875 3475) $PN 106
J 0
(-1865 3485);
DISPLAY 0.617021 (-1865 3485);
PAINT ORANGE (-1865 3485);
FORCEPROP 2 LASTPIN (-1875 3425) $PN 260
J 0
(-1865 3435);
DISPLAY 0.617021 (-1865 3435);
PAINT ORANGE (-1865 3435);
FORCEPROP 2 LASTPIN (-1875 3375) $PN 115
J 0
(-1865 3385);
DISPLAY 0.617021 (-1865 3385);
PAINT ORANGE (-1865 3385);
FORCEPROP 2 LASTPIN (-1875 3325) $PN 253
J 0
(-1865 3335);
DISPLAY 0.617021 (-1865 3335);
PAINT ORANGE (-1865 3335);
FORCEPROP 2 LASTPIN (-1875 3275) $PN 108
J 0
(-1865 3285);
DISPLAY 0.617021 (-1865 3285);
PAINT ORANGE (-1865 3285);
FORCEPROP 2 LASTPIN (-1875 3225) $PN 247
J 0
(-1865 3235);
DISPLAY 0.617021 (-1865 3235);
PAINT ORANGE (-1865 3235);
FORCEPROP 2 LASTPIN (-1875 3175) $PN 102
J 0
(-1865 3185);
DISPLAY 0.617021 (-1865 3185);
PAINT ORANGE (-1865 3185);
FORCEPROP 2 LASTPIN (-1875 3125) $PN 240
J 0
(-1865 3135);
DISPLAY 0.617021 (-1865 3135);
PAINT ORANGE (-1865 3135);
FORCEPROP 2 LASTPIN (-1875 3075) $PN 95
J 0
(-1865 3085);
DISPLAY 0.617021 (-1865 3085);
PAINT ORANGE (-1865 3085);
FORCEPROP 2 LASTPIN (-1875 3025) $PN 249
J 0
(-1865 3035);
DISPLAY 0.617021 (-1865 3035);
PAINT ORANGE (-1865 3035);
FORCEPROP 2 LASTPIN (-1875 2975) $PN 104
J 0
(-1865 2985);
DISPLAY 0.617021 (-1865 2985);
PAINT ORANGE (-1865 2985);
FORCEPROP 2 LASTPIN (-1875 2925) $PN 242
J 0
(-1865 2935);
DISPLAY 0.617021 (-1865 2935);
PAINT ORANGE (-1865 2935);
FORCEPROP 2 LASTPIN (-1875 2875) $PN 97
J 0
(-1865 2885);
DISPLAY 0.617021 (-1865 2885);
PAINT ORANGE (-1865 2885);
FORCEPROP 2 LASTPIN (-1875 2825) $PN 188
J 0
(-1865 2835);
DISPLAY 0.617021 (-1865 2835);
PAINT ORANGE (-1865 2835);
FORCEPROP 2 LASTPIN (-1875 2775) $PN 43
J 0
(-1865 2785);
DISPLAY 0.617021 (-1865 2785);
PAINT ORANGE (-1865 2785);
FORCEPROP 2 LASTPIN (-1875 2725) $PN 181
J 0
(-1865 2735);
DISPLAY 0.617021 (-1865 2735);
PAINT ORANGE (-1865 2735);
FORCEPROP 2 LASTPIN (-1875 2675) $PN 36
J 0
(-1865 2685);
DISPLAY 0.617021 (-1865 2685);
PAINT ORANGE (-1865 2685);
FORCEPROP 2 LASTPIN (-1875 2625) $PN 190
J 0
(-1865 2635);
DISPLAY 0.617021 (-1865 2635);
PAINT ORANGE (-1865 2635);
FORCEPROP 2 LASTPIN (-1875 2575) $PN 45
J 0
(-1865 2585);
DISPLAY 0.617021 (-1865 2585);
PAINT ORANGE (-1865 2585);
FORCEPROP 2 LASTPIN (-1875 2525) $PN 183
J 0
(-1865 2535);
DISPLAY 0.617021 (-1865 2535);
PAINT ORANGE (-1865 2535);
FORCEPROP 2 LASTPIN (-1875 2475) $PN 38
J 0
(-1865 2485);
DISPLAY 0.617021 (-1865 2485);
PAINT ORANGE (-1865 2485);
FORCEPROP 2 LASTPIN (-1875 2425) $PN 177
J 0
(-1865 2435);
DISPLAY 0.617021 (-1865 2435);
PAINT ORANGE (-1865 2435);
FORCEPROP 2 LASTPIN (-1875 2375) $PN 32
J 0
(-1865 2385);
DISPLAY 0.617021 (-1865 2385);
PAINT ORANGE (-1865 2385);
FORCEPROP 2 LASTPIN (-1875 2325) $PN 170
J 0
(-1865 2335);
DISPLAY 0.617021 (-1865 2335);
PAINT ORANGE (-1865 2335);
FORCEPROP 2 LASTPIN (-1875 2275) $PN 25
J 0
(-1865 2285);
DISPLAY 0.617021 (-1865 2285);
PAINT ORANGE (-1865 2285);
FORCEPROP 2 LASTPIN (-1875 2225) $PN 179
J 0
(-1865 2235);
DISPLAY 0.617021 (-1865 2235);
PAINT ORANGE (-1865 2235);
FORCEPROP 2 LASTPIN (-1875 2175) $PN 34
J 0
(-1865 2185);
DISPLAY 0.617021 (-1865 2185);
PAINT ORANGE (-1865 2185);
FORCEPROP 2 LASTPIN (-1875 2125) $PN 172
J 0
(-1865 2135);
DISPLAY 0.617021 (-1865 2135);
PAINT ORANGE (-1865 2135);
FORCEPROP 2 LASTPIN (-1875 2075) $PN 27
J 0
(-1865 2085);
DISPLAY 0.617021 (-1865 2085);
PAINT ORANGE (-1865 2085);
FORCEPROP 2 LASTPIN (-1875 2025) $PN 166
J 0
(-1865 2035);
DISPLAY 0.617021 (-1865 2035);
PAINT ORANGE (-1865 2035);
FORCEPROP 2 LASTPIN (-1875 1975) $PN 21
J 0
(-1865 1985);
DISPLAY 0.617021 (-1865 1985);
PAINT ORANGE (-1865 1985);
FORCEPROP 2 LASTPIN (-1875 1925) $PN 159
J 0
(-1865 1935);
DISPLAY 0.617021 (-1865 1935);
PAINT ORANGE (-1865 1935);
FORCEPROP 2 LASTPIN (-1875 1875) $PN 14
J 0
(-1865 1885);
DISPLAY 0.617021 (-1865 1885);
PAINT ORANGE (-1865 1885);
FORCEPROP 2 LASTPIN (-1875 1825) $PN 168
J 0
(-1865 1835);
DISPLAY 0.617021 (-1865 1835);
PAINT ORANGE (-1865 1835);
FORCEPROP 2 LASTPIN (-1875 1775) $PN 23
J 0
(-1865 1785);
DISPLAY 0.617021 (-1865 1785);
PAINT ORANGE (-1865 1785);
FORCEPROP 2 LASTPIN (-1875 1725) $PN 161
J 0
(-1865 1735);
DISPLAY 0.617021 (-1865 1735);
PAINT ORANGE (-1865 1735);
FORCEPROP 2 LASTPIN (-1875 1675) $PN 16
J 0
(-1865 1685);
DISPLAY 0.617021 (-1865 1685);
PAINT ORANGE (-1865 1685);
FORCEPROP 2 LASTPIN (-1875 1625) $PN 155
J 0
(-1865 1635);
DISPLAY 0.617021 (-1865 1635);
PAINT ORANGE (-1865 1635);
FORCEPROP 2 LASTPIN (-1875 1575) $PN 10
J 0
(-1865 1585);
DISPLAY 0.617021 (-1865 1585);
PAINT ORANGE (-1865 1585);
FORCEPROP 2 LASTPIN (-1875 1525) $PN 148
J 0
(-1865 1535);
DISPLAY 0.617021 (-1865 1535);
PAINT ORANGE (-1865 1535);
FORCEPROP 2 LASTPIN (-1875 1475) $PN 3
J 0
(-1865 1485);
DISPLAY 0.617021 (-1865 1485);
PAINT ORANGE (-1865 1485);
FORCEPROP 2 LASTPIN (-1875 1425) $PN 157
J 0
(-1865 1435);
DISPLAY 0.617021 (-1865 1435);
PAINT ORANGE (-1865 1435);
FORCEPROP 2 LASTPIN (-1875 1375) $PN 12
J 0
(-1865 1385);
DISPLAY 0.617021 (-1865 1385);
PAINT ORANGE (-1865 1385);
FORCEPROP 2 LASTPIN (-1875 1275) $PN 5
J 0
(-1865 1285);
DISPLAY 0.617021 (-1865 1285);
PAINT ORANGE (-1865 1285);
FORCEPROP 2 LASTPIN (-2875 2675) $PN 203
J 2
(-2885 2685);
DISPLAY 0.617021 (-2885 2685);
PAINT ORANGE (-2885 2685);
FORCEPROP 2 LASTPIN (-2875 2625) $PN 60
J 2
(-2885 2635);
DISPLAY 0.617021 (-2885 2635);
PAINT ORANGE (-2885 2635);
FORCEPROP 2 LASTPIN (-2875 3225) $PN 218
J 2
(-2885 3235);
DISPLAY 0.617021 (-2885 3235);
PAINT ORANGE (-2885 3235);
FORCEPROP 2 LASTPIN (-2875 3175) $PN 219
J 2
(-2885 3185);
DISPLAY 0.617021 (-2885 3185);
PAINT ORANGE (-2885 3185);
FORCEPROP 2 LASTPIN (-2875 3125) $PN 74
J 2
(-2885 3135);
DISPLAY 0.617021 (-2885 3135);
PAINT ORANGE (-2885 3135);
FORCEPROP 2 LASTPIN (-2875 3075) $PN 75
J 2
(-2885 3085);
DISPLAY 0.617021 (-2885 3085);
PAINT ORANGE (-2885 3085);
FORCEPROP 2 LASTPIN (-2875 2375) $PN 199
J 2
(-2885 2385);
DISPLAY 0.617021 (-2885 2385);
PAINT ORANGE (-2885 2385);
FORCEPROP 2 LASTPIN (-2875 2325) $PN 54
J 2
(-2885 2335);
DISPLAY 0.617021 (-2885 2335);
PAINT ORANGE (-2885 2335);
FORCEPROP 2 LASTPIN (-2875 2275) $PN 192
J 2
(-2885 2285);
DISPLAY 0.617021 (-2885 2285);
PAINT ORANGE (-2885 2285);
FORCEPROP 2 LASTPIN (-2875 2225) $PN 47
J 2
(-2885 2235);
DISPLAY 0.617021 (-2885 2235);
PAINT ORANGE (-2885 2235);
FORCEPROP 2 LASTPIN (-2875 2175) $PN 201
J 2
(-2885 2185);
DISPLAY 0.617021 (-2885 2185);
PAINT ORANGE (-2885 2185);
FORCEPROP 2 LASTPIN (-2875 2125) $PN 56
J 2
(-2885 2135);
DISPLAY 0.617021 (-2885 2135);
PAINT ORANGE (-2885 2135);
FORCEPROP 2 LASTPIN (-2875 2075) $PN 194
J 2
(-2885 2085);
DISPLAY 0.617021 (-2885 2085);
PAINT ORANGE (-2885 2085);
FORCEPROP 2 LASTPIN (-2875 2025) $PN 49
J 2
(-2885 2035);
DISPLAY 0.617021 (-2885 2035);
PAINT ORANGE (-2885 2035);
FORCEPROP 2 LASTPIN (-2875 2975) $PN 235
J 2
(-2885 2985);
DISPLAY 0.617021 (-2885 2985);
PAINT ORANGE (-2885 2985);
FORCEPROP 2 LASTPIN (-2875 3375) $PN 207
J 2
(-2885 3385);
DISPLAY 0.617021 (-2885 3385);
PAINT ORANGE (-2885 3385);
FORCEPROP 2 LASTPIN (-2875 3325) $PN 63
J 2
(-2885 3335);
DISPLAY 0.617021 (-2885 3335);
PAINT ORANGE (-2885 3335);
FORCEPROP 2 LASTPIN (-2875 3475) $PN 224
J 2
(-2885 3485);
DISPLAY 0.617021 (-2885 3485);
PAINT ORANGE (-2885 3485);
FORCEPROP 2 LASTPIN (-2875 3425) $PN 81
J 2
(-2885 3435);
DISPLAY 0.617021 (-2885 3435);
PAINT ORANGE (-2885 3435);
FORCEPROP 2 LASTPIN (-2875 1775) $PN 208
J 2
(-2885 1785);
DISPLAY 0.617021 (-2885 1785);
PAINT ORANGE (-2885 1785);
FORCEPROP 2 LASTPIN (-2875 1725) $PN 62
J 2
(-2885 1735);
DISPLAY 0.617021 (-2885 1735);
PAINT ORANGE (-2885 1735);
FORCEPROP 2 LASTPIN (-2875 4425) $PN 234
J 2
(-2885 4435);
DISPLAY 0.617021 (-2885 4435);
PAINT ORANGE (-2885 4435);
FORCEPROP 2 LASTPIN (-2875 4375) $PN 82
J 2
(-2885 4385);
DISPLAY 0.617021 (-2885 4385);
PAINT ORANGE (-2885 4385);
FORCEPROP 2 LASTPIN (-2875 4325) $PN 86
J 2
(-2885 4335);
DISPLAY 0.617021 (-2885 4335);
PAINT ORANGE (-2885 4335);
FORCEPROP 2 LASTPIN (-2875 4225) $PN 232
J 2
(-2885 4235);
DISPLAY 0.617021 (-2885 4235);
PAINT ORANGE (-2885 4235);
FORCEPROP 2 LASTPIN (-2875 4175) $PN 65
J 2
(-2885 4185);
DISPLAY 0.617021 (-2885 4185);
PAINT ORANGE (-2885 4185);
FORCEPROP 2 LASTPIN (-2875 4125) $PN 210
J 2
(-2885 4135);
DISPLAY 0.617021 (-2885 4135);
PAINT ORANGE (-2885 4135);
FORCEPROP 2 LASTPIN (-2875 4075) $PN 225
J 2
(-2885 4085);
DISPLAY 0.617021 (-2885 4085);
PAINT ORANGE (-2885 4085);
FORCEPROP 2 LASTPIN (-2875 4025) $PN 66
J 2
(-2885 4035);
DISPLAY 0.617021 (-2885 4035);
PAINT ORANGE (-2885 4035);
FORCEPROP 2 LASTPIN (-2875 3975) $PN 68
J 2
(-2885 3985);
DISPLAY 0.617021 (-2885 3985);
PAINT ORANGE (-2885 3985);
FORCEPROP 2 LASTPIN (-2875 3925) $PN 211
J 2
(-2885 3935);
DISPLAY 0.617021 (-2885 3935);
PAINT ORANGE (-2885 3935);
FORCEPROP 2 LASTPIN (-2875 3875) $PN 69
J 2
(-2885 3885);
DISPLAY 0.617021 (-2885 3885);
PAINT ORANGE (-2885 3885);
FORCEPROP 2 LASTPIN (-2875 3825) $PN 213
J 2
(-2885 3835);
DISPLAY 0.617021 (-2885 3835);
PAINT ORANGE (-2885 3835);
FORCEPROP 2 LASTPIN (-2875 3775) $PN 214
J 2
(-2885 3785);
DISPLAY 0.617021 (-2885 3785);
PAINT ORANGE (-2885 3785);
FORCEPROP 2 LASTPIN (-2875 3725) $PN 71
J 2
(-2885 3735);
DISPLAY 0.617021 (-2885 3735);
PAINT ORANGE (-2885 3735);
FORCEPROP 2 LASTPIN (-2875 3675) $PN 216
J 2
(-2885 3685);
DISPLAY 0.617021 (-2885 3685);
PAINT ORANGE (-2885 3685);
FORCEPROP 2 LASTPIN (-2875 3625) $PN 72
J 2
(-2885 3635);
DISPLAY 0.617021 (-2885 3635);
PAINT ORANGE (-2885 3635);
FORCEPROP 2 LASTPIN (-2875 3575) $PN 79
J 2
(-2885 3585);
DISPLAY 0.617021 (-2885 3585);
PAINT ORANGE (-2885 3585);
FORCEPROP 2 LASTPIN (-1875 4275) $PN 128
J 0
(-1865 4285);
DISPLAY 0.617021 (-1865 4285);
PAINT ORANGE (-1865 4285);
FORCEPROP 2 LASTPIN (-2875 4275) $PN 228
J 2
(-2885 4285);
DISPLAY 0.617021 (-2885 4285);
PAINT ORANGE (-2885 4285);
FORCEPROP 1 LAST MATERIAL SCONN
J 0
(-2825 4625);
DISPLAY 0.617021 (-2825 4625);
PAINT SKYBLUE (-2825 4625);
FORCEPROP 1 LAST PACK_TYPE PIP
J 0
(-2825 4725);
PAINT SKYBLUE (-2825 4725);
DISPLAY INVISIBLE (-2825 4725);
FORCEPROP 2 LAST BOM_COST MEM
J 0
(-2375 2775);
PAINT ORANGE (-2375 2775);
DISPLAY INVISIBLE (-2375 2775);
FORCEPROP 2 LAST CDS_LIB mstr_sconn
J 0
(-2375 2775);
PAINT ORANGE (-2375 2775);
DISPLAY INVISIBLE (-2375 2775);
FORCEPROP 2 LAST SEC_TYPE PIP
J 0
(-2800 4750);
DISPLAY 1.021277 (-2800 4750);
PAINT ORANGE (-2800 4750);
DISPLAY INVISIBLE (-2800 4750);
FORCEPROP 2 LAST SEC 1
J 0
(-2800 4750);
DISPLAY 0.680851 (-2800 4750);
PAINT MONO (-2800 4750);
DISPLAY INVISIBLE (-2800 4750);
FORCEPROP 2 LAST CDS_LOCATION J1G1
J 0
(-2825 4675);
DISPLAY 0.617021 (-2825 4675);
PAINT AQUA (-2825 4675);
DISPLAY INVISIBLE (-2825 4675);
FORCEPROP 1 LAST PATH I111
J 0
(-2375 4625);
PAINT GREEN (-2375 4625);
DISPLAY INVISIBLE (-2375 4625);
FORCEPROP 2 LAST ROOM DDR4_CH_G
J 0
(-2375 2775);
PAINT ORANGE (-2375 2775);
DISPLAY INVISIBLE (-2375 2775);
FORCEADD TAP..6
(-3125 4425);
FORCEPROP 3 LASTPIN (-3075 4425) SIG_NAME M_G_MA<17>
J 0
(-3065 4435);
DISPLAY 0.659574 (-3065 4435);
PAINT MONO (-3065 4435);
DISPLAY INVISIBLE (-3065 4435);
FORCEPROP 1 LASTPIN (-3075 4425) BN 17
J 0
(-3125 4435);
DISPLAY 0.617021 (-3125 4435);
PAINT PINK (-3125 4435);
FORCEPROP 2 LAST CDS_LIB mstr_standard
J 0
(-3125 4425);
DISPLAY 0.787234 (-3125 4425);
PAINT MONO (-3125 4425);
DISPLAY INVISIBLE (-3125 4425);
FORCEPROP 1 LAST BODY_TYPE PLUMBING
J 0
(-3125 4375);
DISPLAY 1.234043 (-3125 4375);
PAINT GREEN (-3125 4375);
DISPLAY INVISIBLE (-3125 4375);
FORCEPROP 1 LAST HDL_TAP TRUE
J 0
(-2800 4300);
DISPLAY 1.234043 (-2800 4300);
PAINT GREEN (-2800 4300);
DISPLAY INVISIBLE (-2800 4300);
FORCEPROP 1 LAST PATH I112
J 0
(-3125 4425);
DISPLAY 0.936170 (-3125 4425);
PAINT GREEN (-3125 4425);
DISPLAY INVISIBLE (-3125 4425);
FORCEADD TAP..6
(-3125 4375);
FORCEPROP 3 LASTPIN (-3075 4375) SIG_NAME M_G_MA<16>
J 0
(-3065 4385);
DISPLAY 0.659574 (-3065 4385);
PAINT MONO (-3065 4385);
DISPLAY INVISIBLE (-3065 4385);
FORCEPROP 1 LASTPIN (-3075 4375) BN 16
J 0
(-3125 4385);
DISPLAY 0.617021 (-3125 4385);
PAINT PINK (-3125 4385);
FORCEPROP 2 LAST CDS_LIB mstr_standard
J 2
(-3125 4375);
DISPLAY 0.787234 (-3125 4375);
PAINT MONO (-3125 4375);
DISPLAY INVISIBLE (-3125 4375);
FORCEPROP 1 LAST BODY_TYPE PLUMBING
J 0
(-3125 4325);
DISPLAY 1.234043 (-3125 4325);
PAINT GREEN (-3125 4325);
DISPLAY INVISIBLE (-3125 4325);
FORCEPROP 1 LAST HDL_TAP TRUE
J 0
(-2800 4250);
DISPLAY 1.234043 (-2800 4250);
PAINT GREEN (-2800 4250);
DISPLAY INVISIBLE (-2800 4250);
FORCEPROP 1 LAST PATH I113
J 0
(-3125 4375);
DISPLAY 0.936170 (-3125 4375);
PAINT GREEN (-3125 4375);
DISPLAY INVISIBLE (-3125 4375);
FORCEADD TAP..6
(-3125 4325);
FORCEPROP 3 LASTPIN (-3075 4325) SIG_NAME M_G_MA<15>
J 0
(-3065 4335);
DISPLAY 0.659574 (-3065 4335);
PAINT MONO (-3065 4335);
DISPLAY INVISIBLE (-3065 4335);
FORCEPROP 1 LASTPIN (-3075 4325) BN 15
J 0
(-3125 4335);
DISPLAY 0.617021 (-3125 4335);
PAINT PINK (-3125 4335);
FORCEPROP 2 LAST CDS_LIB mstr_standard
J 2
(-3125 4325);
DISPLAY 0.787234 (-3125 4325);
PAINT MONO (-3125 4325);
DISPLAY INVISIBLE (-3125 4325);
FORCEPROP 1 LAST BODY_TYPE PLUMBING
J 0
(-3125 4275);
DISPLAY 1.234043 (-3125 4275);
PAINT GREEN (-3125 4275);
DISPLAY INVISIBLE (-3125 4275);
FORCEPROP 1 LAST HDL_TAP TRUE
J 0
(-2800 4200);
DISPLAY 1.234043 (-2800 4200);
PAINT GREEN (-2800 4200);
DISPLAY INVISIBLE (-2800 4200);
FORCEPROP 1 LAST PATH I114
J 0
(-3125 4325);
DISPLAY 0.936170 (-3125 4325);
PAINT GREEN (-3125 4325);
DISPLAY INVISIBLE (-3125 4325);
FORCEADD TAP..6
(-3125 4275);
FORCEPROP 3 LASTPIN (-3075 4275) SIG_NAME M_G_MA<14>
J 0
(-3065 4285);
DISPLAY 0.659574 (-3065 4285);
PAINT MONO (-3065 4285);
DISPLAY INVISIBLE (-3065 4285);
FORCEPROP 1 LASTPIN (-3075 4275) BN 14
J 0
(-3125 4285);
DISPLAY 0.617021 (-3125 4285);
PAINT PINK (-3125 4285);
FORCEPROP 2 LAST CDS_LIB mstr_standard
J 2
(-3125 4275);
DISPLAY 0.787234 (-3125 4275);
PAINT MONO (-3125 4275);
DISPLAY INVISIBLE (-3125 4275);
FORCEPROP 1 LAST BODY_TYPE PLUMBING
J 0
(-3125 4225);
DISPLAY 1.234043 (-3125 4225);
PAINT GREEN (-3125 4225);
DISPLAY INVISIBLE (-3125 4225);
FORCEPROP 1 LAST HDL_TAP TRUE
J 0
(-2800 4150);
DISPLAY 1.234043 (-2800 4150);
PAINT GREEN (-2800 4150);
DISPLAY INVISIBLE (-2800 4150);
FORCEPROP 1 LAST PATH I115
J 0
(-3125 4275);
DISPLAY 0.936170 (-3125 4275);
PAINT GREEN (-3125 4275);
DISPLAY INVISIBLE (-3125 4275);
FORCEADD TAP..6
(-3125 4125);
FORCEPROP 3 LASTPIN (-3075 4125) SIG_NAME M_G_MA<11>
J 0
(-3065 4135);
DISPLAY 0.659574 (-3065 4135);
PAINT MONO (-3065 4135);
DISPLAY INVISIBLE (-3065 4135);
FORCEPROP 1 LASTPIN (-3075 4125) BN 11
J 0
(-3125 4135);
DISPLAY 0.617021 (-3125 4135);
PAINT PINK (-3125 4135);
FORCEPROP 2 LAST CDS_LIB mstr_standard
J 2
(-3125 4125);
DISPLAY 0.787234 (-3125 4125);
PAINT MONO (-3125 4125);
DISPLAY INVISIBLE (-3125 4125);
FORCEPROP 1 LAST BODY_TYPE PLUMBING
J 0
(-3125 4075);
DISPLAY 1.234043 (-3125 4075);
PAINT GREEN (-3125 4075);
DISPLAY INVISIBLE (-3125 4075);
FORCEPROP 1 LAST HDL_TAP TRUE
J 0
(-2800 4000);
DISPLAY 1.234043 (-2800 4000);
PAINT GREEN (-2800 4000);
DISPLAY INVISIBLE (-2800 4000);
FORCEPROP 1 LAST PATH I116
J 0
(-3125 4125);
DISPLAY 0.936170 (-3125 4125);
PAINT GREEN (-3125 4125);
DISPLAY INVISIBLE (-3125 4125);
FORCEADD TAP..6
(-3125 4225);
FORCEPROP 3 LASTPIN (-3075 4225) SIG_NAME M_G_MA<13>
J 0
(-3065 4235);
DISPLAY 0.659574 (-3065 4235);
PAINT MONO (-3065 4235);
DISPLAY INVISIBLE (-3065 4235);
FORCEPROP 1 LASTPIN (-3075 4225) BN 13
J 0
(-3125 4235);
DISPLAY 0.617021 (-3125 4235);
PAINT PINK (-3125 4235);
FORCEPROP 2 LAST CDS_LIB mstr_standard
J 2
(-3125 4225);
DISPLAY 0.787234 (-3125 4225);
PAINT MONO (-3125 4225);
DISPLAY INVISIBLE (-3125 4225);
FORCEPROP 1 LAST BODY_TYPE PLUMBING
J 0
(-3125 4175);
DISPLAY 1.234043 (-3125 4175);
PAINT GREEN (-3125 4175);
DISPLAY INVISIBLE (-3125 4175);
FORCEPROP 1 LAST HDL_TAP TRUE
J 0
(-2800 4100);
DISPLAY 1.234043 (-2800 4100);
PAINT GREEN (-2800 4100);
DISPLAY INVISIBLE (-2800 4100);
FORCEPROP 1 LAST PATH I117
J 0
(-3125 4225);
DISPLAY 0.936170 (-3125 4225);
PAINT GREEN (-3125 4225);
DISPLAY INVISIBLE (-3125 4225);
FORCEADD TAP..6
(-3125 4175);
FORCEPROP 3 LASTPIN (-3075 4175) SIG_NAME M_G_MA<12>
J 0
(-3065 4185);
DISPLAY 0.659574 (-3065 4185);
PAINT MONO (-3065 4185);
DISPLAY INVISIBLE (-3065 4185);
FORCEPROP 1 LASTPIN (-3075 4175) BN 12
J 0
(-3125 4185);
DISPLAY 0.617021 (-3125 4185);
PAINT PINK (-3125 4185);
FORCEPROP 2 LAST CDS_LIB mstr_standard
J 2
(-3125 4175);
DISPLAY 0.787234 (-3125 4175);
PAINT MONO (-3125 4175);
DISPLAY INVISIBLE (-3125 4175);
FORCEPROP 1 LAST BODY_TYPE PLUMBING
J 0
(-3125 4125);
DISPLAY 1.234043 (-3125 4125);
PAINT GREEN (-3125 4125);
DISPLAY INVISIBLE (-3125 4125);
FORCEPROP 1 LAST HDL_TAP TRUE
J 0
(-2800 4050);
DISPLAY 1.234043 (-2800 4050);
PAINT GREEN (-2800 4050);
DISPLAY INVISIBLE (-2800 4050);
FORCEPROP 1 LAST PATH I118
J 0
(-3125 4175);
DISPLAY 0.936170 (-3125 4175);
PAINT GREEN (-3125 4175);
DISPLAY INVISIBLE (-3125 4175);
FORCEADD TAP..6
(-3125 4075);
FORCEPROP 3 LASTPIN (-3075 4075) SIG_NAME M_G_MA<10>
J 0
(-3065 4085);
DISPLAY 0.659574 (-3065 4085);
PAINT MONO (-3065 4085);
DISPLAY INVISIBLE (-3065 4085);
FORCEPROP 1 LASTPIN (-3075 4075) BN 10
J 0
(-3125 4085);
DISPLAY 0.617021 (-3125 4085);
PAINT PINK (-3125 4085);
FORCEPROP 2 LAST CDS_LIB mstr_standard
J 2
(-3125 4075);
DISPLAY 0.787234 (-3125 4075);
PAINT MONO (-3125 4075);
DISPLAY INVISIBLE (-3125 4075);
FORCEPROP 1 LAST BODY_TYPE PLUMBING
J 0
(-3125 4025);
DISPLAY 1.234043 (-3125 4025);
PAINT GREEN (-3125 4025);
DISPLAY INVISIBLE (-3125 4025);
FORCEPROP 1 LAST HDL_TAP TRUE
J 0
(-2800 3950);
DISPLAY 1.234043 (-2800 3950);
PAINT GREEN (-2800 3950);
DISPLAY INVISIBLE (-2800 3950);
FORCEPROP 1 LAST PATH I119
J 0
(-3125 4075);
DISPLAY 0.936170 (-3125 4075);
PAINT GREEN (-3125 4075);
DISPLAY INVISIBLE (-3125 4075);
FORCEADD TAP..6
R 2
(700 4950);
FORCEPROP 3 LASTPIN (650 4950) SIG_NAME M_G_DQS_DP<16>
J 0
(660 4960);
DISPLAY 0.659574 (660 4960);
PAINT MONO (660 4960);
DISPLAY INVISIBLE (660 4960);
FORCEPROP 1 LASTPIN (650 4950) BN 16
J 2
(700 4960);
DISPLAY 0.617021 (700 4960);
PAINT PINK (700 4960);
FORCEPROP 2 LAST CDS_LIB mstr_standard
J 0
(700 4950);
DISPLAY 0.787234 (700 4950);
PAINT MONO (700 4950);
DISPLAY INVISIBLE (700 4950);
FORCEPROP 1 LAST BODY_TYPE PLUMBING
J 2
(700 4900);
DISPLAY 1.234043 (700 4900);
PAINT GREEN (700 4900);
DISPLAY INVISIBLE (700 4900);
FORCEPROP 1 LAST HDL_TAP TRUE
J 2
(375 4825);
DISPLAY 1.234043 (375 4825);
PAINT GREEN (375 4825);
DISPLAY INVISIBLE (375 4825);
FORCEPROP 1 LAST PATH I12
J 2
(700 4950);
DISPLAY 0.936170 (700 4950);
PAINT GREEN (700 4950);
DISPLAY INVISIBLE (700 4950);
FORCEADD TAP..6
(-3125 4025);
FORCEPROP 3 LASTPIN (-3075 4025) SIG_NAME M_G_MA<9>
J 0
(-3065 4035);
DISPLAY 0.659574 (-3065 4035);
PAINT MONO (-3065 4035);
DISPLAY INVISIBLE (-3065 4035);
FORCEPROP 1 LASTPIN (-3075 4025) BN 9
J 0
(-3125 4035);
DISPLAY 0.617021 (-3125 4035);
PAINT PINK (-3125 4035);
FORCEPROP 2 LAST CDS_LIB mstr_standard
J 2
(-3125 4025);
DISPLAY 0.787234 (-3125 4025);
PAINT MONO (-3125 4025);
DISPLAY INVISIBLE (-3125 4025);
FORCEPROP 1 LAST BODY_TYPE PLUMBING
J 0
(-3125 3975);
DISPLAY 1.234043 (-3125 3975);
PAINT GREEN (-3125 3975);
DISPLAY INVISIBLE (-3125 3975);
FORCEPROP 1 LAST HDL_TAP TRUE
J 0
(-2800 3900);
DISPLAY 1.234043 (-2800 3900);
PAINT GREEN (-2800 3900);
DISPLAY INVISIBLE (-2800 3900);
FORCEPROP 1 LAST PATH I120
J 0
(-3125 4025);
DISPLAY 0.936170 (-3125 4025);
PAINT GREEN (-3125 4025);
DISPLAY INVISIBLE (-3125 4025);
FORCEADD TAP..6
(-3125 3875);
FORCEPROP 3 LASTPIN (-3075 3875) SIG_NAME M_G_MA<6>
J 0
(-3065 3885);
DISPLAY 0.659574 (-3065 3885);
PAINT MONO (-3065 3885);
DISPLAY INVISIBLE (-3065 3885);
FORCEPROP 1 LASTPIN (-3075 3875) BN 6
J 0
(-3125 3885);
DISPLAY 0.617021 (-3125 3885);
PAINT PINK (-3125 3885);
FORCEPROP 2 LAST CDS_LIB mstr_standard
J 2
(-3125 3875);
DISPLAY 0.787234 (-3125 3875);
PAINT MONO (-3125 3875);
DISPLAY INVISIBLE (-3125 3875);
FORCEPROP 1 LAST BODY_TYPE PLUMBING
J 0
(-3125 3825);
DISPLAY 1.234043 (-3125 3825);
PAINT GREEN (-3125 3825);
DISPLAY INVISIBLE (-3125 3825);
FORCEPROP 1 LAST HDL_TAP TRUE
J 0
(-2800 3750);
DISPLAY 1.234043 (-2800 3750);
PAINT GREEN (-2800 3750);
DISPLAY INVISIBLE (-2800 3750);
FORCEPROP 1 LAST PATH I121
J 0
(-3125 3875);
DISPLAY 0.936170 (-3125 3875);
PAINT GREEN (-3125 3875);
DISPLAY INVISIBLE (-3125 3875);
FORCEADD TAP..6
(-3125 3975);
FORCEPROP 3 LASTPIN (-3075 3975) SIG_NAME M_G_MA<8>
J 0
(-3065 3985);
DISPLAY 0.659574 (-3065 3985);
PAINT MONO (-3065 3985);
DISPLAY INVISIBLE (-3065 3985);
FORCEPROP 1 LASTPIN (-3075 3975) BN 8
J 0
(-3125 3985);
DISPLAY 0.617021 (-3125 3985);
PAINT PINK (-3125 3985);
FORCEPROP 2 LAST CDS_LIB mstr_standard
J 2
(-3125 3975);
DISPLAY 0.787234 (-3125 3975);
PAINT MONO (-3125 3975);
DISPLAY INVISIBLE (-3125 3975);
FORCEPROP 1 LAST BODY_TYPE PLUMBING
J 0
(-3125 3925);
DISPLAY 1.234043 (-3125 3925);
PAINT GREEN (-3125 3925);
DISPLAY INVISIBLE (-3125 3925);
FORCEPROP 1 LAST HDL_TAP TRUE
J 0
(-2800 3850);
DISPLAY 1.234043 (-2800 3850);
PAINT GREEN (-2800 3850);
DISPLAY INVISIBLE (-2800 3850);
FORCEPROP 1 LAST PATH I122
J 0
(-3125 3975);
DISPLAY 0.936170 (-3125 3975);
PAINT GREEN (-3125 3975);
DISPLAY INVISIBLE (-3125 3975);
FORCEADD TAP..6
(-3125 3925);
FORCEPROP 3 LASTPIN (-3075 3925) SIG_NAME M_G_MA<7>
J 0
(-3065 3935);
DISPLAY 0.659574 (-3065 3935);
PAINT MONO (-3065 3935);
DISPLAY INVISIBLE (-3065 3935);
FORCEPROP 1 LASTPIN (-3075 3925) BN 7
J 0
(-3125 3935);
DISPLAY 0.617021 (-3125 3935);
PAINT PINK (-3125 3935);
FORCEPROP 2 LAST CDS_LIB mstr_standard
J 2
(-3125 3925);
DISPLAY 0.787234 (-3125 3925);
PAINT MONO (-3125 3925);
DISPLAY INVISIBLE (-3125 3925);
FORCEPROP 1 LAST BODY_TYPE PLUMBING
J 0
(-3125 3875);
DISPLAY 1.234043 (-3125 3875);
PAINT GREEN (-3125 3875);
DISPLAY INVISIBLE (-3125 3875);
FORCEPROP 1 LAST HDL_TAP TRUE
J 0
(-2800 3800);
DISPLAY 1.234043 (-2800 3800);
PAINT GREEN (-2800 3800);
DISPLAY INVISIBLE (-2800 3800);
FORCEPROP 1 LAST PATH I123
J 0
(-3125 3925);
DISPLAY 0.936170 (-3125 3925);
PAINT GREEN (-3125 3925);
DISPLAY INVISIBLE (-3125 3925);
FORCEADD TAP..6
(-3125 3825);
FORCEPROP 3 LASTPIN (-3075 3825) SIG_NAME M_G_MA<5>
J 0
(-3065 3835);
DISPLAY 0.659574 (-3065 3835);
PAINT MONO (-3065 3835);
DISPLAY INVISIBLE (-3065 3835);
FORCEPROP 1 LASTPIN (-3075 3825) BN 5
J 0
(-3125 3835);
DISPLAY 0.617021 (-3125 3835);
PAINT PINK (-3125 3835);
FORCEPROP 2 LAST CDS_LIB mstr_standard
J 2
(-3125 3825);
DISPLAY 0.787234 (-3125 3825);
PAINT MONO (-3125 3825);
DISPLAY INVISIBLE (-3125 3825);
FORCEPROP 1 LAST BODY_TYPE PLUMBING
J 0
(-3125 3775);
DISPLAY 1.234043 (-3125 3775);
PAINT GREEN (-3125 3775);
DISPLAY INVISIBLE (-3125 3775);
FORCEPROP 1 LAST HDL_TAP TRUE
J 0
(-2800 3700);
DISPLAY 1.234043 (-2800 3700);
PAINT GREEN (-2800 3700);
DISPLAY INVISIBLE (-2800 3700);
FORCEPROP 1 LAST PATH I124
J 0
(-3125 3825);
DISPLAY 0.936170 (-3125 3825);
PAINT GREEN (-3125 3825);
DISPLAY INVISIBLE (-3125 3825);
FORCEADD TAP..6
(-3125 3775);
FORCEPROP 3 LASTPIN (-3075 3775) SIG_NAME M_G_MA<4>
J 0
(-3065 3785);
DISPLAY 0.659574 (-3065 3785);
PAINT MONO (-3065 3785);
DISPLAY INVISIBLE (-3065 3785);
FORCEPROP 1 LASTPIN (-3075 3775) BN 4
J 0
(-3125 3785);
DISPLAY 0.617021 (-3125 3785);
PAINT PINK (-3125 3785);
FORCEPROP 2 LAST CDS_LIB mstr_standard
J 2
(-3125 3775);
DISPLAY 0.787234 (-3125 3775);
PAINT MONO (-3125 3775);
DISPLAY INVISIBLE (-3125 3775);
FORCEPROP 1 LAST BODY_TYPE PLUMBING
J 0
(-3125 3725);
DISPLAY 1.234043 (-3125 3725);
PAINT GREEN (-3125 3725);
DISPLAY INVISIBLE (-3125 3725);
FORCEPROP 1 LAST HDL_TAP TRUE
J 0
(-2800 3650);
DISPLAY 1.234043 (-2800 3650);
PAINT GREEN (-2800 3650);
DISPLAY INVISIBLE (-2800 3650);
FORCEPROP 1 LAST PATH I125
J 0
(-3125 3775);
DISPLAY 0.936170 (-3125 3775);
PAINT GREEN (-3125 3775);
DISPLAY INVISIBLE (-3125 3775);
FORCEADD TAP..6
(-3125 3725);
FORCEPROP 3 LASTPIN (-3075 3725) SIG_NAME M_G_MA<3>
J 0
(-3065 3735);
DISPLAY 0.659574 (-3065 3735);
PAINT MONO (-3065 3735);
DISPLAY INVISIBLE (-3065 3735);
FORCEPROP 1 LASTPIN (-3075 3725) BN 3
J 0
(-3125 3735);
DISPLAY 0.617021 (-3125 3735);
PAINT PINK (-3125 3735);
FORCEPROP 2 LAST CDS_LIB mstr_standard
J 2
(-3125 3725);
DISPLAY 0.787234 (-3125 3725);
PAINT MONO (-3125 3725);
DISPLAY INVISIBLE (-3125 3725);
FORCEPROP 1 LAST BODY_TYPE PLUMBING
J 0
(-3125 3675);
DISPLAY 1.234043 (-3125 3675);
PAINT GREEN (-3125 3675);
DISPLAY INVISIBLE (-3125 3675);
FORCEPROP 1 LAST HDL_TAP TRUE
J 0
(-2800 3600);
DISPLAY 1.234043 (-2800 3600);
PAINT GREEN (-2800 3600);
DISPLAY INVISIBLE (-2800 3600);
FORCEPROP 1 LAST PATH I126
J 0
(-3125 3725);
DISPLAY 0.936170 (-3125 3725);
PAINT GREEN (-3125 3725);
DISPLAY INVISIBLE (-3125 3725);
FORCEADD TAP..6
(-3125 3675);
FORCEPROP 3 LASTPIN (-3075 3675) SIG_NAME M_G_MA<2>
J 0
(-3065 3685);
DISPLAY 0.659574 (-3065 3685);
PAINT MONO (-3065 3685);
DISPLAY INVISIBLE (-3065 3685);
FORCEPROP 1 LASTPIN (-3075 3675) BN 2
J 0
(-3125 3685);
DISPLAY 0.617021 (-3125 3685);
PAINT PINK (-3125 3685);
FORCEPROP 2 LAST CDS_LIB mstr_standard
J 2
(-3125 3675);
DISPLAY 0.787234 (-3125 3675);
PAINT MONO (-3125 3675);
DISPLAY INVISIBLE (-3125 3675);
FORCEPROP 1 LAST BODY_TYPE PLUMBING
J 0
(-3125 3625);
DISPLAY 1.234043 (-3125 3625);
PAINT GREEN (-3125 3625);
DISPLAY INVISIBLE (-3125 3625);
FORCEPROP 1 LAST HDL_TAP TRUE
J 0
(-2800 3550);
DISPLAY 1.234043 (-2800 3550);
PAINT GREEN (-2800 3550);
DISPLAY INVISIBLE (-2800 3550);
FORCEPROP 1 LAST PATH I127
J 0
(-3125 3675);
DISPLAY 0.936170 (-3125 3675);
PAINT GREEN (-3125 3675);
DISPLAY INVISIBLE (-3125 3675);
FORCEADD TAP..6
(-3125 3625);
FORCEPROP 3 LASTPIN (-3075 3625) SIG_NAME M_G_MA<1>
J 0
(-3065 3635);
DISPLAY 0.659574 (-3065 3635);
PAINT MONO (-3065 3635);
DISPLAY INVISIBLE (-3065 3635);
FORCEPROP 1 LASTPIN (-3075 3625) BN 1
J 0
(-3125 3635);
DISPLAY 0.617021 (-3125 3635);
PAINT PINK (-3125 3635);
FORCEPROP 2 LAST CDS_LIB mstr_standard
J 2
(-3125 3625);
DISPLAY 0.787234 (-3125 3625);
PAINT MONO (-3125 3625);
DISPLAY INVISIBLE (-3125 3625);
FORCEPROP 1 LAST BODY_TYPE PLUMBING
J 0
(-3125 3575);
DISPLAY 1.234043 (-3125 3575);
PAINT GREEN (-3125 3575);
DISPLAY INVISIBLE (-3125 3575);
FORCEPROP 1 LAST HDL_TAP TRUE
J 0
(-2800 3500);
DISPLAY 1.234043 (-2800 3500);
PAINT GREEN (-2800 3500);
DISPLAY INVISIBLE (-2800 3500);
FORCEPROP 1 LAST PATH I128
J 0
(-3125 3625);
DISPLAY 0.936170 (-3125 3625);
PAINT GREEN (-3125 3625);
DISPLAY INVISIBLE (-3125 3625);
FORCEADD TAP..6
(-3125 3575);
FORCEPROP 3 LASTPIN (-3075 3575) SIG_NAME M_G_MA<0>
J 0
(-3065 3585);
DISPLAY 0.659574 (-3065 3585);
PAINT MONO (-3065 3585);
DISPLAY INVISIBLE (-3065 3585);
FORCEPROP 1 LASTPIN (-3075 3575) BN 0
J 0
(-3125 3585);
DISPLAY 0.617021 (-3125 3585);
PAINT PINK (-3125 3585);
FORCEPROP 2 LAST CDS_LIB mstr_standard
J 2
(-3125 3575);
DISPLAY 0.787234 (-3125 3575);
PAINT MONO (-3125 3575);
DISPLAY INVISIBLE (-3125 3575);
FORCEPROP 1 LAST BODY_TYPE PLUMBING
J 0
(-3125 3525);
DISPLAY 1.234043 (-3125 3525);
PAINT GREEN (-3125 3525);
DISPLAY INVISIBLE (-3125 3525);
FORCEPROP 1 LAST HDL_TAP TRUE
J 0
(-2800 3450);
DISPLAY 1.234043 (-2800 3450);
PAINT GREEN (-2800 3450);
DISPLAY INVISIBLE (-2800 3450);
FORCEPROP 1 LAST PATH I129
J 0
(-3125 3575);
DISPLAY 0.936170 (-3125 3575);
PAINT GREEN (-3125 3575);
DISPLAY INVISIBLE (-3125 3575);
FORCEADD TAP..6
R 2
(700 4450);
FORCEPROP 3 LASTPIN (650 4450) SIG_NAME M_G_DQS_DP<11>
J 0
(660 4460);
DISPLAY 0.659574 (660 4460);
PAINT MONO (660 4460);
DISPLAY INVISIBLE (660 4460);
FORCEPROP 1 LASTPIN (650 4450) BN 11
J 2
(700 4460);
DISPLAY 0.617021 (700 4460);
PAINT PINK (700 4460);
FORCEPROP 2 LAST CDS_LIB mstr_standard
J 0
(700 4450);
DISPLAY 0.787234 (700 4450);
PAINT MONO (700 4450);
DISPLAY INVISIBLE (700 4450);
FORCEPROP 1 LAST BODY_TYPE PLUMBING
J 2
(700 4400);
DISPLAY 1.234043 (700 4400);
PAINT GREEN (700 4400);
DISPLAY INVISIBLE (700 4400);
FORCEPROP 1 LAST HDL_TAP TRUE
J 2
(375 4325);
DISPLAY 1.234043 (375 4325);
PAINT GREEN (375 4325);
DISPLAY INVISIBLE (375 4325);
FORCEPROP 1 LAST PATH I13
J 2
(700 4450);
DISPLAY 0.936170 (700 4450);
PAINT GREEN (700 4450);
DISPLAY INVISIBLE (700 4450);
FORCEADD TAP..6
(-3125 3475);
FORCEPROP 3 LASTPIN (-3075 3475) SIG_NAME M_G_BA<1>
J 0
(-3065 3485);
DISPLAY 0.659574 (-3065 3485);
PAINT MONO (-3065 3485);
DISPLAY INVISIBLE (-3065 3485);
FORCEPROP 1 LASTPIN (-3075 3475) BN 1
J 0
(-3125 3485);
DISPLAY 0.617021 (-3125 3485);
PAINT PINK (-3125 3485);
FORCEPROP 2 LAST CDS_LIB mstr_standard
J 0
(-3125 3475);
DISPLAY 0.787234 (-3125 3475);
PAINT MONO (-3125 3475);
DISPLAY INVISIBLE (-3125 3475);
FORCEPROP 1 LAST BODY_TYPE PLUMBING
J 0
(-3125 3425);
DISPLAY 1.234043 (-3125 3425);
PAINT GREEN (-3125 3425);
DISPLAY INVISIBLE (-3125 3425);
FORCEPROP 1 LAST HDL_TAP TRUE
J 0
(-2800 3350);
DISPLAY 1.234043 (-2800 3350);
PAINT GREEN (-2800 3350);
DISPLAY INVISIBLE (-2800 3350);
FORCEPROP 1 LAST PATH I130
J 0
(-3125 3475);
DISPLAY 0.936170 (-3125 3475);
PAINT GREEN (-3125 3475);
DISPLAY INVISIBLE (-3125 3475);
FORCEADD OFFPAGE..1
(-3775 4475);
FORCEPROP 2 LAST $XR1 78 
J 0
(-4086 4475);
DISPLAY 0.638298 (-4086 4475);
PAINT MONO (-4086 4475);
FORCEPROP 2 LAST $XR0 57 
J 0
(-3996 4475);
DISPLAY 0.638298 (-3996 4475);
PAINT MONO (-3996 4475);
FORCEPROP 2 LAST CDS_LIB mstr_standard
J 0
(-3775 4475);
DISPLAY 0.787234 (-3775 4475);
PAINT MONO (-3775 4475);
DISPLAY INVISIBLE (-3775 4475);
FORCEPROP 1 LAST OFFPAGE TRUE
J 0
(-3450 4350);
DISPLAY 0.936170 (-3450 4350);
PAINT GREEN (-3450 4350);
DISPLAY INVISIBLE (-3450 4350);
FORCEPROP 1 LAST COMMENT_BODY TRUE
J 0
(-3650 4375);
DISPLAY 0.936170 (-3650 4375);
PAINT GREEN (-3650 4375);
DISPLAY INVISIBLE (-3650 4375);
FORCEPROP 2 LAST PATH I131
J 0
(-3725 4550);
DISPLAY 0.787234 (-3725 4550);
PAINT MONO (-3725 4550);
DISPLAY INVISIBLE (-3725 4550);
FORCEADD OFFPAGE..1
(-3775 3550);
FORCEPROP 2 LAST $XR1 78 
J 0
(-4086 3550);
DISPLAY 0.638298 (-4086 3550);
PAINT MONO (-4086 3550);
FORCEPROP 2 LAST $XR0 57 
J 0
(-3996 3550);
DISPLAY 0.638298 (-3996 3550);
PAINT MONO (-3996 3550);
FORCEPROP 2 LAST CDS_LIB mstr_standard
J 0
(-3775 3550);
DISPLAY 0.787234 (-3775 3550);
PAINT MONO (-3775 3550);
DISPLAY INVISIBLE (-3775 3550);
FORCEPROP 1 LAST OFFPAGE TRUE
J 0
(-3450 3425);
DISPLAY 0.936170 (-3450 3425);
PAINT GREEN (-3450 3425);
DISPLAY INVISIBLE (-3450 3425);
FORCEPROP 1 LAST COMMENT_BODY TRUE
J 0
(-3650 3450);
DISPLAY 0.936170 (-3650 3450);
PAINT GREEN (-3650 3450);
DISPLAY INVISIBLE (-3650 3450);
FORCEPROP 2 LAST PATH I132
J 0
(-3725 3625);
DISPLAY 0.787234 (-3725 3625);
PAINT MONO (-3725 3625);
DISPLAY INVISIBLE (-3725 3625);
FORCEADD TAP..6
(-3125 3425);
FORCEPROP 3 LASTPIN (-3075 3425) SIG_NAME M_G_BA<0>
J 0
(-3065 3435);
DISPLAY 0.659574 (-3065 3435);
PAINT MONO (-3065 3435);
DISPLAY INVISIBLE (-3065 3435);
FORCEPROP 1 LASTPIN (-3075 3425) BN 0
J 0
(-3125 3435);
DISPLAY 0.617021 (-3125 3435);
PAINT PINK (-3125 3435);
FORCEPROP 2 LAST CDS_LIB mstr_standard
J 0
(-3125 3425);
DISPLAY 0.787234 (-3125 3425);
PAINT MONO (-3125 3425);
DISPLAY INVISIBLE (-3125 3425);
FORCEPROP 1 LAST BODY_TYPE PLUMBING
J 0
(-3125 3375);
DISPLAY 1.234043 (-3125 3375);
PAINT GREEN (-3125 3375);
DISPLAY INVISIBLE (-3125 3375);
FORCEPROP 1 LAST HDL_TAP TRUE
J 0
(-2800 3300);
DISPLAY 1.234043 (-2800 3300);
PAINT GREEN (-2800 3300);
DISPLAY INVISIBLE (-2800 3300);
FORCEPROP 1 LAST PATH I133
J 0
(-3125 3425);
DISPLAY 0.936170 (-3125 3425);
PAINT GREEN (-3125 3425);
DISPLAY INVISIBLE (-3125 3425);
FORCEADD TAP..6
(-3125 3375);
FORCEPROP 3 LASTPIN (-3075 3375) SIG_NAME M_G_BG<1>
J 0
(-3065 3385);
DISPLAY 0.659574 (-3065 3385);
PAINT MONO (-3065 3385);
DISPLAY INVISIBLE (-3065 3385);
FORCEPROP 1 LASTPIN (-3075 3375) BN 1
J 0
(-3125 3385);
DISPLAY 0.617021 (-3125 3385);
PAINT PINK (-3125 3385);
FORCEPROP 2 LAST CDS_LIB mstr_standard
J 0
(-3125 3375);
DISPLAY 0.787234 (-3125 3375);
PAINT MONO (-3125 3375);
DISPLAY INVISIBLE (-3125 3375);
FORCEPROP 1 LAST BODY_TYPE PLUMBING
J 0
(-3125 3325);
DISPLAY 1.234043 (-3125 3325);
PAINT GREEN (-3125 3325);
DISPLAY INVISIBLE (-3125 3325);
FORCEPROP 1 LAST HDL_TAP TRUE
J 0
(-2800 3250);
DISPLAY 1.234043 (-2800 3250);
PAINT GREEN (-2800 3250);
DISPLAY INVISIBLE (-2800 3250);
FORCEPROP 1 LAST PATH I134
J 0
(-3125 3375);
DISPLAY 0.936170 (-3125 3375);
PAINT GREEN (-3125 3375);
DISPLAY INVISIBLE (-3125 3375);
FORCEADD TAP..6
(-3125 3325);
FORCEPROP 3 LASTPIN (-3075 3325) SIG_NAME M_G_BG<0>
J 0
(-3065 3335);
DISPLAY 0.659574 (-3065 3335);
PAINT MONO (-3065 3335);
DISPLAY INVISIBLE (-3065 3335);
FORCEPROP 1 LASTPIN (-3075 3325) BN 0
J 0
(-3125 3335);
DISPLAY 0.617021 (-3125 3335);
PAINT PINK (-3125 3335);
FORCEPROP 2 LAST CDS_LIB mstr_standard
J 0
(-3125 3325);
DISPLAY 0.787234 (-3125 3325);
PAINT MONO (-3125 3325);
DISPLAY INVISIBLE (-3125 3325);
FORCEPROP 1 LAST BODY_TYPE PLUMBING
J 0
(-3125 3275);
DISPLAY 1.234043 (-3125 3275);
PAINT GREEN (-3125 3275);
DISPLAY INVISIBLE (-3125 3275);
FORCEPROP 1 LAST HDL_TAP TRUE
J 0
(-2800 3200);
DISPLAY 1.234043 (-2800 3200);
PAINT GREEN (-2800 3200);
DISPLAY INVISIBLE (-2800 3200);
FORCEPROP 1 LAST PATH I135
J 0
(-3125 3325);
DISPLAY 0.936170 (-3125 3325);
PAINT GREEN (-3125 3325);
DISPLAY INVISIBLE (-3125 3325);
FORCEADD OFFPAGE..1
(-3775 3025);
FORCEPROP 2 LAST $XR1 78 
J 0
(-4086 3025);
DISPLAY 0.638298 (-4086 3025);
PAINT MONO (-4086 3025);
FORCEPROP 2 LAST $XR0 57 
J 0
(-3996 3025);
DISPLAY 0.638298 (-3996 3025);
PAINT MONO (-3996 3025);
FORCEPROP 2 LAST CDS_LIB mstr_standard
J 0
(-3775 3025);
DISPLAY 0.787234 (-3775 3025);
PAINT MONO (-3775 3025);
DISPLAY INVISIBLE (-3775 3025);
FORCEPROP 1 LAST OFFPAGE TRUE
J 0
(-3450 2900);
DISPLAY 0.936170 (-3450 2900);
PAINT GREEN (-3450 2900);
DISPLAY INVISIBLE (-3450 2900);
FORCEPROP 1 LAST COMMENT_BODY TRUE
J 0
(-3650 2925);
DISPLAY 0.936170 (-3650 2925);
PAINT GREEN (-3650 2925);
DISPLAY INVISIBLE (-3650 2925);
FORCEPROP 2 LAST PATH I136
J 0
(-3725 3100);
DISPLAY 0.787234 (-3725 3100);
PAINT MONO (-3725 3100);
DISPLAY INVISIBLE (-3725 3100);
FORCEADD OFFPAGE..1
(-3775 3425);
FORCEPROP 2 LAST $XR1 78 
J 0
(-4086 3425);
DISPLAY 0.638298 (-4086 3425);
PAINT MONO (-4086 3425);
FORCEPROP 2 LAST $XR0 57 
J 0
(-3996 3425);
DISPLAY 0.638298 (-3996 3425);
PAINT MONO (-3996 3425);
FORCEPROP 2 LAST CDS_LIB mstr_standard
J 0
(-3775 3425);
DISPLAY 0.787234 (-3775 3425);
PAINT MONO (-3775 3425);
DISPLAY INVISIBLE (-3775 3425);
FORCEPROP 1 LAST OFFPAGE TRUE
J 0
(-3450 3300);
DISPLAY 0.936170 (-3450 3300);
PAINT GREEN (-3450 3300);
DISPLAY INVISIBLE (-3450 3300);
FORCEPROP 1 LAST COMMENT_BODY TRUE
J 0
(-3650 3325);
DISPLAY 0.936170 (-3650 3325);
PAINT GREEN (-3650 3325);
DISPLAY INVISIBLE (-3650 3325);
FORCEPROP 2 LAST PATH I137
J 0
(-3725 3500);
DISPLAY 0.787234 (-3725 3500);
PAINT MONO (-3725 3500);
DISPLAY INVISIBLE (-3725 3500);
FORCEADD TAP..6
(-3125 2375);
FORCEPROP 3 LASTPIN (-3075 2375) SIG_NAME M_G_ECC<6>
J 0
(-3065 2385);
DISPLAY 0.659574 (-3065 2385);
PAINT MONO (-3065 2385);
DISPLAY INVISIBLE (-3065 2385);
FORCEPROP 1 LASTPIN (-3075 2375) BN 6
J 0
(-3125 2385);
DISPLAY 0.617021 (-3125 2385);
PAINT PINK (-3125 2385);
FORCEPROP 2 LAST CDS_LIB mstr_standard
J 0
(-3125 2375);
DISPLAY 0.787234 (-3125 2375);
PAINT MONO (-3125 2375);
DISPLAY INVISIBLE (-3125 2375);
FORCEPROP 1 LAST BODY_TYPE PLUMBING
J 0
(-3125 2325);
DISPLAY 1.234043 (-3125 2325);
PAINT GREEN (-3125 2325);
DISPLAY INVISIBLE (-3125 2325);
FORCEPROP 1 LAST HDL_TAP TRUE
J 0
(-2800 2250);
DISPLAY 1.234043 (-2800 2250);
PAINT GREEN (-2800 2250);
DISPLAY INVISIBLE (-2800 2250);
FORCEPROP 1 LAST PATH I138
J 0
(-3125 2375);
DISPLAY 0.936170 (-3125 2375);
PAINT GREEN (-3125 2375);
DISPLAY INVISIBLE (-3125 2375);
FORCEADD TAP..6
(-3125 2325);
FORCEPROP 3 LASTPIN (-3075 2325) SIG_NAME M_G_ECC<7>
J 0
(-3065 2335);
DISPLAY 0.659574 (-3065 2335);
PAINT MONO (-3065 2335);
DISPLAY INVISIBLE (-3065 2335);
FORCEPROP 1 LASTPIN (-3075 2325) BN 7
J 0
(-3125 2335);
DISPLAY 0.617021 (-3125 2335);
PAINT PINK (-3125 2335);
FORCEPROP 2 LAST CDS_LIB mstr_standard
J 0
(-3125 2325);
DISPLAY 0.787234 (-3125 2325);
PAINT MONO (-3125 2325);
DISPLAY INVISIBLE (-3125 2325);
FORCEPROP 1 LAST BODY_TYPE PLUMBING
J 0
(-3125 2275);
DISPLAY 1.234043 (-3125 2275);
PAINT GREEN (-3125 2275);
DISPLAY INVISIBLE (-3125 2275);
FORCEPROP 1 LAST HDL_TAP TRUE
J 0
(-2800 2200);
DISPLAY 1.234043 (-2800 2200);
PAINT GREEN (-2800 2200);
DISPLAY INVISIBLE (-2800 2200);
FORCEPROP 1 LAST PATH I139
J 0
(-3125 2325);
DISPLAY 0.936170 (-3125 2325);
PAINT GREEN (-3125 2325);
DISPLAY INVISIBLE (-3125 2325);
FORCEADD TAP..6
R 2
(700 4550);
FORCEPROP 3 LASTPIN (650 4550) SIG_NAME M_G_DQS_DP<12>
J 0
(660 4560);
DISPLAY 0.659574 (660 4560);
PAINT MONO (660 4560);
DISPLAY INVISIBLE (660 4560);
FORCEPROP 1 LASTPIN (650 4550) BN 12
J 2
(700 4560);
DISPLAY 0.617021 (700 4560);
PAINT PINK (700 4560);
FORCEPROP 2 LAST CDS_LIB mstr_standard
J 0
(700 4550);
DISPLAY 0.787234 (700 4550);
PAINT MONO (700 4550);
DISPLAY INVISIBLE (700 4550);
FORCEPROP 1 LAST BODY_TYPE PLUMBING
J 2
(700 4500);
DISPLAY 1.234043 (700 4500);
PAINT GREEN (700 4500);
DISPLAY INVISIBLE (700 4500);
FORCEPROP 1 LAST HDL_TAP TRUE
J 2
(375 4425);
DISPLAY 1.234043 (375 4425);
PAINT GREEN (375 4425);
DISPLAY INVISIBLE (375 4425);
FORCEPROP 1 LAST PATH I14
J 2
(700 4550);
DISPLAY 0.936170 (700 4550);
PAINT GREEN (700 4550);
DISPLAY INVISIBLE (700 4550);
FORCEADD TAP..6
(-3125 2275);
FORCEPROP 3 LASTPIN (-3075 2275) SIG_NAME M_G_ECC<4>
J 0
(-3065 2285);
DISPLAY 0.659574 (-3065 2285);
PAINT MONO (-3065 2285);
DISPLAY INVISIBLE (-3065 2285);
FORCEPROP 1 LASTPIN (-3075 2275) BN 4
J 0
(-3125 2285);
DISPLAY 0.617021 (-3125 2285);
PAINT PINK (-3125 2285);
FORCEPROP 2 LAST CDS_LIB mstr_standard
J 0
(-3125 2275);
DISPLAY 0.787234 (-3125 2275);
PAINT MONO (-3125 2275);
DISPLAY INVISIBLE (-3125 2275);
FORCEPROP 1 LAST BODY_TYPE PLUMBING
J 0
(-3125 2225);
DISPLAY 1.234043 (-3125 2225);
PAINT GREEN (-3125 2225);
DISPLAY INVISIBLE (-3125 2225);
FORCEPROP 1 LAST HDL_TAP TRUE
J 0
(-2800 2150);
DISPLAY 1.234043 (-2800 2150);
PAINT GREEN (-2800 2150);
DISPLAY INVISIBLE (-2800 2150);
FORCEPROP 1 LAST PATH I140
J 0
(-3125 2275);
DISPLAY 0.936170 (-3125 2275);
PAINT GREEN (-3125 2275);
DISPLAY INVISIBLE (-3125 2275);
FORCEADD TAP..6
(-3125 2225);
FORCEPROP 3 LASTPIN (-3075 2225) SIG_NAME M_G_ECC<5>
J 0
(-3065 2235);
DISPLAY 0.659574 (-3065 2235);
PAINT MONO (-3065 2235);
DISPLAY INVISIBLE (-3065 2235);
FORCEPROP 1 LASTPIN (-3075 2225) BN 5
J 0
(-3125 2235);
DISPLAY 0.617021 (-3125 2235);
PAINT PINK (-3125 2235);
FORCEPROP 2 LAST CDS_LIB mstr_standard
J 0
(-3125 2225);
DISPLAY 0.787234 (-3125 2225);
PAINT MONO (-3125 2225);
DISPLAY INVISIBLE (-3125 2225);
FORCEPROP 1 LAST BODY_TYPE PLUMBING
J 0
(-3125 2175);
DISPLAY 1.234043 (-3125 2175);
PAINT GREEN (-3125 2175);
DISPLAY INVISIBLE (-3125 2175);
FORCEPROP 1 LAST HDL_TAP TRUE
J 0
(-2800 2100);
DISPLAY 1.234043 (-2800 2100);
PAINT GREEN (-2800 2100);
DISPLAY INVISIBLE (-2800 2100);
FORCEPROP 1 LAST PATH I141
J 0
(-3125 2225);
DISPLAY 0.936170 (-3125 2225);
PAINT GREEN (-3125 2225);
DISPLAY INVISIBLE (-3125 2225);
FORCEADD TAP..6
(-3125 2075);
FORCEPROP 3 LASTPIN (-3075 2075) SIG_NAME M_G_ECC<0>
J 0
(-3065 2085);
DISPLAY 0.659574 (-3065 2085);
PAINT MONO (-3065 2085);
DISPLAY INVISIBLE (-3065 2085);
FORCEPROP 1 LASTPIN (-3075 2075) BN 0
J 0
(-3125 2085);
DISPLAY 0.617021 (-3125 2085);
PAINT PINK (-3125 2085);
FORCEPROP 2 LAST CDS_LIB mstr_standard
J 0
(-3125 2075);
DISPLAY 0.787234 (-3125 2075);
PAINT MONO (-3125 2075);
DISPLAY INVISIBLE (-3125 2075);
FORCEPROP 1 LAST BODY_TYPE PLUMBING
J 0
(-3125 2025);
DISPLAY 1.234043 (-3125 2025);
PAINT GREEN (-3125 2025);
DISPLAY INVISIBLE (-3125 2025);
FORCEPROP 1 LAST HDL_TAP TRUE
J 0
(-2800 1950);
DISPLAY 1.234043 (-2800 1950);
PAINT GREEN (-2800 1950);
DISPLAY INVISIBLE (-2800 1950);
FORCEPROP 1 LAST PATH I142
J 0
(-3125 2075);
DISPLAY 0.936170 (-3125 2075);
PAINT GREEN (-3125 2075);
DISPLAY INVISIBLE (-3125 2075);
FORCEADD TAP..6
(-3125 2125);
FORCEPROP 3 LASTPIN (-3075 2125) SIG_NAME M_G_ECC<3>
J 0
(-3065 2135);
DISPLAY 0.659574 (-3065 2135);
PAINT MONO (-3065 2135);
DISPLAY INVISIBLE (-3065 2135);
FORCEPROP 1 LASTPIN (-3075 2125) BN 3
J 0
(-3125 2135);
DISPLAY 0.617021 (-3125 2135);
PAINT PINK (-3125 2135);
FORCEPROP 2 LAST CDS_LIB mstr_standard
J 0
(-3125 2125);
DISPLAY 0.787234 (-3125 2125);
PAINT MONO (-3125 2125);
DISPLAY INVISIBLE (-3125 2125);
FORCEPROP 1 LAST BODY_TYPE PLUMBING
J 0
(-3125 2075);
DISPLAY 1.234043 (-3125 2075);
PAINT GREEN (-3125 2075);
DISPLAY INVISIBLE (-3125 2075);
FORCEPROP 1 LAST HDL_TAP TRUE
J 0
(-2800 2000);
DISPLAY 1.234043 (-2800 2000);
PAINT GREEN (-2800 2000);
DISPLAY INVISIBLE (-2800 2000);
FORCEPROP 1 LAST PATH I143
J 0
(-3125 2125);
DISPLAY 0.936170 (-3125 2125);
PAINT GREEN (-3125 2125);
DISPLAY INVISIBLE (-3125 2125);
FORCEADD TAP..6
(-3125 2175);
FORCEPROP 3 LASTPIN (-3075 2175) SIG_NAME M_G_ECC<2>
J 0
(-3065 2185);
DISPLAY 0.659574 (-3065 2185);
PAINT MONO (-3065 2185);
DISPLAY INVISIBLE (-3065 2185);
FORCEPROP 1 LASTPIN (-3075 2175) BN 2
J 0
(-3125 2185);
DISPLAY 0.617021 (-3125 2185);
PAINT PINK (-3125 2185);
FORCEPROP 2 LAST CDS_LIB mstr_standard
J 0
(-3125 2175);
DISPLAY 0.787234 (-3125 2175);
PAINT MONO (-3125 2175);
DISPLAY INVISIBLE (-3125 2175);
FORCEPROP 1 LAST BODY_TYPE PLUMBING
J 0
(-3125 2125);
DISPLAY 1.234043 (-3125 2125);
PAINT GREEN (-3125 2125);
DISPLAY INVISIBLE (-3125 2125);
FORCEPROP 1 LAST HDL_TAP TRUE
J 0
(-2800 2050);
DISPLAY 1.234043 (-2800 2050);
PAINT GREEN (-2800 2050);
DISPLAY INVISIBLE (-2800 2050);
FORCEPROP 1 LAST PATH I144
J 0
(-3125 2175);
DISPLAY 0.936170 (-3125 2175);
PAINT GREEN (-3125 2175);
DISPLAY INVISIBLE (-3125 2175);
FORCEADD TAP..6
(-3125 2025);
FORCEPROP 3 LASTPIN (-3075 2025) SIG_NAME M_G_ECC<1>
J 0
(-3065 2035);
DISPLAY 0.659574 (-3065 2035);
PAINT MONO (-3065 2035);
DISPLAY INVISIBLE (-3065 2035);
FORCEPROP 1 LASTPIN (-3075 2025) BN 1
J 0
(-3125 2035);
DISPLAY 0.617021 (-3125 2035);
PAINT PINK (-3125 2035);
FORCEPROP 2 LAST CDS_LIB mstr_standard
J 0
(-3125 2025);
DISPLAY 0.787234 (-3125 2025);
PAINT MONO (-3125 2025);
DISPLAY INVISIBLE (-3125 2025);
FORCEPROP 1 LAST BODY_TYPE PLUMBING
J 0
(-3125 1975);
DISPLAY 1.234043 (-3125 1975);
PAINT GREEN (-3125 1975);
DISPLAY INVISIBLE (-3125 1975);
FORCEPROP 1 LAST HDL_TAP TRUE
J 0
(-2800 1900);
DISPLAY 1.234043 (-2800 1900);
PAINT GREEN (-2800 1900);
DISPLAY INVISIBLE (-2800 1900);
FORCEPROP 1 LAST PATH I145
J 0
(-3125 2025);
DISPLAY 0.936170 (-3125 2025);
PAINT GREEN (-3125 2025);
DISPLAY INVISIBLE (-3125 2025);
FORCEADD OFFPAGE..1
(-3925 1725);
FORCEPROP 2 LAST $XR1 78 
J 0
(-4266 1725);
DISPLAY 0.638298 (-4266 1725);
PAINT MONO (-4266 1725);
FORCEPROP 2 LAST $XR0 57 
J 0
(-4176 1725);
DISPLAY 0.638298 (-4176 1725);
PAINT MONO (-4176 1725);
FORCEPROP 2 LAST CDS_LIB mstr_standard
J 0
(-3925 1725);
DISPLAY 0.787234 (-3925 1725);
PAINT MONO (-3925 1725);
DISPLAY INVISIBLE (-3925 1725);
FORCEPROP 1 LAST OFFPAGE TRUE
J 0
(-3600 1600);
DISPLAY 0.936170 (-3600 1600);
PAINT GREEN (-3600 1600);
DISPLAY INVISIBLE (-3600 1600);
FORCEPROP 1 LAST COMMENT_BODY TRUE
J 0
(-3800 1625);
DISPLAY 0.936170 (-3800 1625);
PAINT GREEN (-3800 1625);
DISPLAY INVISIBLE (-3800 1625);
FORCEPROP 2 LAST PATH I147
J 0
(-3875 1800);
DISPLAY 0.787234 (-3875 1800);
PAINT MONO (-3875 1800);
DISPLAY INVISIBLE (-3875 1800);
FORCEADD OFFPAGE..5
(-3950 1775);
FORCEPROP 2 LAST $XR1 57 
J 0
(-4294 1775);
DISPLAY 0.638298 (-4294 1775);
PAINT MONO (-4294 1775);
FORCEPROP 2 LAST $XR0 78 
J 0
(-4204 1775);
DISPLAY 0.638298 (-4204 1775);
PAINT MONO (-4204 1775);
FORCEPROP 2 LAST CDS_LIB mstr_standard
J 0
(-3950 1775);
DISPLAY 0.787234 (-3950 1775);
PAINT MONO (-3950 1775);
DISPLAY INVISIBLE (-3950 1775);
FORCEPROP 1 LAST OFFPAGE TRUE
J 0
(-3625 1650);
DISPLAY 1.404255 (-3625 1650);
PAINT GREEN (-3625 1650);
DISPLAY INVISIBLE (-3625 1650);
FORCEPROP 1 LAST COMMENT_BODY TRUE
J 0
(-3850 1700);
DISPLAY 1.404255 (-3850 1700);
PAINT GREEN (-3850 1700);
DISPLAY INVISIBLE (-3850 1700);
FORCEPROP 2 LAST PATH I148
J 0
(-3900 1850);
DISPLAY 0.787234 (-3900 1850);
PAINT MONO (-3900 1850);
DISPLAY INVISIBLE (-3900 1850);
FORCEADD OFFPAGE..1
(-3775 2325);
FORCEPROP 2 LAST $XR5 82 
J 0
(-4446 2325);
DISPLAY 0.638298 (-4446 2325);
PAINT MONO (-4446 2325);
FORCEPROP 2 LAST $XR4 81 
J 0
(-4356 2325);
DISPLAY 0.638298 (-4356 2325);
PAINT MONO (-4356 2325);
FORCEPROP 2 LAST $XR3 80 
J 0
(-4266 2325);
DISPLAY 0.638298 (-4266 2325);
PAINT MONO (-4266 2325);
FORCEPROP 2 LAST $XR2 79 
J 0
(-4176 2325);
DISPLAY 0.638298 (-4176 2325);
PAINT MONO (-4176 2325);
FORCEPROP 2 LAST $XR1 78 
J 0
(-4086 2325);
DISPLAY 0.638298 (-4086 2325);
PAINT MONO (-4086 2325);
FORCEPROP 2 LAST $XR0 55 
J 0
(-3996 2325);
DISPLAY 0.638298 (-3996 2325);
PAINT MONO (-3996 2325);
FORCEPROP 2 LAST CDS_LIB mstr_standard
J 0
(-3775 2325);
DISPLAY 0.787234 (-3775 2325);
PAINT MONO (-3775 2325);
DISPLAY INVISIBLE (-3775 2325);
FORCEPROP 1 LAST OFFPAGE TRUE
J 0
(-3450 2200);
DISPLAY 0.936170 (-3450 2200);
PAINT GREEN (-3450 2200);
DISPLAY INVISIBLE (-3450 2200);
FORCEPROP 1 LAST COMMENT_BODY TRUE
J 0
(-3650 2225);
DISPLAY 0.936170 (-3650 2225);
PAINT GREEN (-3650 2225);
DISPLAY INVISIBLE (-3650 2225);
FORCEPROP 2 LAST PATH I149
J 0
(-3725 2400);
DISPLAY 0.787234 (-3725 2400);
PAINT MONO (-3725 2400);
DISPLAY INVISIBLE (-3725 2400);
FORCEADD TAP..6
R 2
(700 4650);
FORCEPROP 3 LASTPIN (650 4650) SIG_NAME M_G_DQS_DP<13>
J 0
(660 4660);
DISPLAY 0.659574 (660 4660);
PAINT MONO (660 4660);
DISPLAY INVISIBLE (660 4660);
FORCEPROP 1 LASTPIN (650 4650) BN 13
J 2
(700 4660);
DISPLAY 0.617021 (700 4660);
PAINT PINK (700 4660);
FORCEPROP 2 LAST CDS_LIB mstr_standard
J 0
(700 4650);
DISPLAY 0.787234 (700 4650);
PAINT MONO (700 4650);
DISPLAY INVISIBLE (700 4650);
FORCEPROP 1 LAST BODY_TYPE PLUMBING
J 2
(700 4600);
DISPLAY 1.234043 (700 4600);
PAINT GREEN (700 4600);
DISPLAY INVISIBLE (700 4600);
FORCEPROP 1 LAST HDL_TAP TRUE
J 2
(375 4525);
DISPLAY 1.234043 (375 4525);
PAINT GREEN (375 4525);
DISPLAY INVISIBLE (375 4525);
FORCEPROP 1 LAST PATH I15
J 2
(700 4650);
DISPLAY 0.936170 (700 4650);
PAINT GREEN (700 4650);
DISPLAY INVISIBLE (700 4650);
FORCEADD OFFPAGE..6
(-3775 2425);
FORCEPROP 2 LAST $XR1 78 
J 0
(-4114 2425);
DISPLAY 0.638298 (-4114 2425);
PAINT MONO (-4114 2425);
FORCEPROP 2 LAST $XR0 57 
J 0
(-4024 2425);
DISPLAY 0.638298 (-4024 2425);
PAINT MONO (-4024 2425);
FORCEPROP 2 LAST CDS_LIB mstr_standard
J 0
(-3775 2425);
DISPLAY 0.787234 (-3775 2425);
PAINT MONO (-3775 2425);
DISPLAY INVISIBLE (-3775 2425);
FORCEPROP 1 LAST OFFPAGE TRUE
J 0
(-3450 2300);
DISPLAY 0.936170 (-3450 2300);
PAINT GREEN (-3450 2300);
DISPLAY INVISIBLE (-3450 2300);
FORCEPROP 1 LAST COMMENT_BODY TRUE
J 0
(-3675 2350);
DISPLAY 0.936170 (-3675 2350);
PAINT GREEN (-3675 2350);
DISPLAY INVISIBLE (-3675 2350);
FORCEPROP 2 LAST PATH I150
J 0
(-3725 2500);
DISPLAY 0.787234 (-3725 2500);
PAINT MONO (-3725 2500);
DISPLAY INVISIBLE (-3725 2500);
FORCEADD TAP..6
(-3125 3225);
FORCEPROP 3 LASTPIN (-3075 3225) SIG_NAME M_G_CLK_DP<1>
J 0
(-3065 3235);
DISPLAY 0.659574 (-3065 3235);
PAINT MONO (-3065 3235);
DISPLAY INVISIBLE (-3065 3235);
FORCEPROP 1 LASTPIN (-3075 3225) BN 1
J 0
(-3125 3235);
DISPLAY 0.617021 (-3125 3235);
PAINT PINK (-3125 3235);
FORCEPROP 2 LAST CDS_LIB mstr_standard
J 0
(-3125 3225);
DISPLAY 0.787234 (-3125 3225);
PAINT MONO (-3125 3225);
DISPLAY INVISIBLE (-3125 3225);
FORCEPROP 1 LAST BODY_TYPE PLUMBING
J 0
(-3125 3175);
DISPLAY 1.234043 (-3125 3175);
PAINT GREEN (-3125 3175);
DISPLAY INVISIBLE (-3125 3175);
FORCEPROP 1 LAST HDL_TAP TRUE
J 0
(-2800 3100);
DISPLAY 1.234043 (-2800 3100);
PAINT GREEN (-2800 3100);
DISPLAY INVISIBLE (-2800 3100);
FORCEPROP 1 LAST PATH I152
J 0
(-3125 3225);
DISPLAY 0.936170 (-3125 3225);
PAINT GREEN (-3125 3225);
DISPLAY INVISIBLE (-3125 3225);
FORCEADD TAP..6
(-3125 3125);
FORCEPROP 3 LASTPIN (-3075 3125) SIG_NAME M_G_CLK_DP<0>
J 0
(-3065 3135);
DISPLAY 0.659574 (-3065 3135);
PAINT MONO (-3065 3135);
DISPLAY INVISIBLE (-3065 3135);
FORCEPROP 1 LASTPIN (-3075 3125) BN 0
J 0
(-3125 3135);
DISPLAY 0.617021 (-3125 3135);
PAINT PINK (-3125 3135);
FORCEPROP 2 LAST CDS_LIB mstr_standard
J 0
(-3125 3125);
DISPLAY 0.787234 (-3125 3125);
PAINT MONO (-3125 3125);
DISPLAY INVISIBLE (-3125 3125);
FORCEPROP 1 LAST BODY_TYPE PLUMBING
J 0
(-3125 3075);
DISPLAY 1.234043 (-3125 3075);
PAINT GREEN (-3125 3075);
DISPLAY INVISIBLE (-3125 3075);
FORCEPROP 1 LAST HDL_TAP TRUE
J 0
(-2800 3000);
DISPLAY 1.234043 (-2800 3000);
PAINT GREEN (-2800 3000);
DISPLAY INVISIBLE (-2800 3000);
FORCEPROP 1 LAST PATH I153
J 0
(-3125 3125);
DISPLAY 0.936170 (-3125 3125);
PAINT GREEN (-3125 3125);
DISPLAY INVISIBLE (-3125 3125);
FORCEADD OFFPAGE..1
(-3775 3300);
FORCEPROP 2 LAST $XR1 78 
J 0
(-4086 3300);
DISPLAY 0.638298 (-4086 3300);
PAINT MONO (-4086 3300);
FORCEPROP 2 LAST $XR0 57 
J 0
(-3996 3300);
DISPLAY 0.638298 (-3996 3300);
PAINT MONO (-3996 3300);
FORCEPROP 2 LAST CDS_LIB mstr_standard
J 0
(-3775 3300);
DISPLAY 0.787234 (-3775 3300);
PAINT MONO (-3775 3300);
DISPLAY INVISIBLE (-3775 3300);
FORCEPROP 1 LAST OFFPAGE TRUE
J 0
(-3450 3175);
DISPLAY 0.936170 (-3450 3175);
PAINT GREEN (-3450 3175);
DISPLAY INVISIBLE (-3450 3175);
FORCEPROP 1 LAST COMMENT_BODY TRUE
J 0
(-3650 3200);
DISPLAY 0.936170 (-3650 3200);
PAINT GREEN (-3650 3200);
DISPLAY INVISIBLE (-3650 3200);
FORCEPROP 2 LAST PATH I154
J 0
(-3725 3375);
DISPLAY 0.787234 (-3725 3375);
PAINT MONO (-3725 3375);
DISPLAY INVISIBLE (-3725 3375);
FORCEADD OFFPAGE..1
(-3775 3250);
FORCEPROP 2 LAST $XR1 78 
J 0
(-4086 3250);
DISPLAY 0.638298 (-4086 3250);
PAINT MONO (-4086 3250);
FORCEPROP 2 LAST $XR0 57 
J 0
(-3996 3250);
DISPLAY 0.638298 (-3996 3250);
PAINT MONO (-3996 3250);
FORCEPROP 2 LAST CDS_LIB mstr_standard
J 0
(-3775 3250);
DISPLAY 0.787234 (-3775 3250);
PAINT MONO (-3775 3250);
DISPLAY INVISIBLE (-3775 3250);
FORCEPROP 1 LAST OFFPAGE TRUE
J 0
(-3450 3125);
DISPLAY 0.936170 (-3450 3125);
PAINT GREEN (-3450 3125);
DISPLAY INVISIBLE (-3450 3125);
FORCEPROP 1 LAST COMMENT_BODY TRUE
J 0
(-3650 3150);
DISPLAY 0.936170 (-3650 3150);
PAINT GREEN (-3650 3150);
DISPLAY INVISIBLE (-3650 3150);
FORCEPROP 2 LAST PATH I155
J 0
(-3725 3325);
DISPLAY 0.787234 (-3725 3325);
PAINT MONO (-3725 3325);
DISPLAY INVISIBLE (-3725 3325);
FORCEADD TAP..6
(-3325 3175);
FORCEPROP 3 LASTPIN (-3275 3175) SIG_NAME M_G_CLK_DN<1>
J 0
(-3265 3185);
DISPLAY 0.659574 (-3265 3185);
PAINT MONO (-3265 3185);
DISPLAY INVISIBLE (-3265 3185);
FORCEPROP 1 LASTPIN (-3275 3175) BN 1
J 0
(-3325 3185);
DISPLAY 0.617021 (-3325 3185);
PAINT PINK (-3325 3185);
FORCEPROP 2 LAST CDS_LIB mstr_standard
J 0
(-3325 3175);
DISPLAY 0.787234 (-3325 3175);
PAINT MONO (-3325 3175);
DISPLAY INVISIBLE (-3325 3175);
FORCEPROP 1 LAST BODY_TYPE PLUMBING
J 0
(-3325 3125);
DISPLAY 1.234043 (-3325 3125);
PAINT GREEN (-3325 3125);
DISPLAY INVISIBLE (-3325 3125);
FORCEPROP 1 LAST HDL_TAP TRUE
J 0
(-3000 3050);
DISPLAY 1.234043 (-3000 3050);
PAINT GREEN (-3000 3050);
DISPLAY INVISIBLE (-3000 3050);
FORCEPROP 1 LAST PATH I156
J 0
(-3325 3175);
DISPLAY 0.936170 (-3325 3175);
PAINT GREEN (-3325 3175);
DISPLAY INVISIBLE (-3325 3175);
FORCEADD TAP..6
(-3325 3075);
FORCEPROP 3 LASTPIN (-3275 3075) SIG_NAME M_G_CLK_DN<0>
J 0
(-3265 3085);
DISPLAY 0.659574 (-3265 3085);
PAINT MONO (-3265 3085);
DISPLAY INVISIBLE (-3265 3085);
FORCEPROP 1 LASTPIN (-3275 3075) BN 0
J 0
(-3325 3085);
DISPLAY 0.617021 (-3325 3085);
PAINT PINK (-3325 3085);
FORCEPROP 2 LAST CDS_LIB mstr_standard
J 0
(-3325 3075);
DISPLAY 0.787234 (-3325 3075);
PAINT MONO (-3325 3075);
DISPLAY INVISIBLE (-3325 3075);
FORCEPROP 1 LAST BODY_TYPE PLUMBING
J 0
(-3325 3025);
DISPLAY 1.234043 (-3325 3025);
PAINT GREEN (-3325 3025);
DISPLAY INVISIBLE (-3325 3025);
FORCEPROP 1 LAST HDL_TAP TRUE
J 0
(-3000 2950);
DISPLAY 1.234043 (-3000 2950);
PAINT GREEN (-3000 2950);
DISPLAY INVISIBLE (-3000 2950);
FORCEPROP 1 LAST PATH I157
J 0
(-3325 3075);
DISPLAY 0.936170 (-3325 3075);
PAINT GREEN (-3325 3075);
DISPLAY INVISIBLE (-3325 3075);
FORCEADD TAP..6
(-3125 2925);
FORCEPROP 3 LASTPIN (-3075 2925) SIG_NAME M_G_CS_N<3>
J 0
(-3065 2935);
DISPLAY 0.659574 (-3065 2935);
PAINT MONO (-3065 2935);
DISPLAY INVISIBLE (-3065 2935);
FORCEPROP 1 LASTPIN (-3075 2925) BN 3
J 0
(-3125 2935);
DISPLAY 0.617021 (-3125 2935);
PAINT PINK (-3125 2935);
FORCEPROP 2 LAST CDS_LIB mstr_standard
J 0
(-3125 2925);
DISPLAY 0.787234 (-3125 2925);
PAINT MONO (-3125 2925);
DISPLAY INVISIBLE (-3125 2925);
FORCEPROP 1 LAST BODY_TYPE PLUMBING
J 0
(-3125 2875);
DISPLAY 1.234043 (-3125 2875);
PAINT GREEN (-3125 2875);
DISPLAY INVISIBLE (-3125 2875);
FORCEPROP 1 LAST HDL_TAP TRUE
J 0
(-2800 2800);
DISPLAY 1.234043 (-2800 2800);
PAINT GREEN (-2800 2800);
DISPLAY INVISIBLE (-2800 2800);
FORCEPROP 1 LAST PATH I158
J 0
(-3125 2925);
DISPLAY 0.936170 (-3125 2925);
PAINT GREEN (-3125 2925);
DISPLAY INVISIBLE (-3125 2925);
FORCEADD TAP..6
(-3125 2875);
FORCEPROP 3 LASTPIN (-3075 2875) SIG_NAME M_G_CS_N<2>
J 0
(-3065 2885);
DISPLAY 0.659574 (-3065 2885);
PAINT MONO (-3065 2885);
DISPLAY INVISIBLE (-3065 2885);
FORCEPROP 1 LASTPIN (-3075 2875) BN 2
J 0
(-3125 2885);
DISPLAY 0.617021 (-3125 2885);
PAINT PINK (-3125 2885);
FORCEPROP 2 LAST CDS_LIB mstr_standard
J 0
(-3125 2875);
DISPLAY 0.787234 (-3125 2875);
PAINT MONO (-3125 2875);
DISPLAY INVISIBLE (-3125 2875);
FORCEPROP 1 LAST BODY_TYPE PLUMBING
J 0
(-3125 2825);
DISPLAY 1.234043 (-3125 2825);
PAINT GREEN (-3125 2825);
DISPLAY INVISIBLE (-3125 2825);
FORCEPROP 1 LAST HDL_TAP TRUE
J 0
(-2800 2750);
DISPLAY 1.234043 (-2800 2750);
PAINT GREEN (-2800 2750);
DISPLAY INVISIBLE (-2800 2750);
FORCEPROP 1 LAST PATH I159
J 0
(-3125 2875);
DISPLAY 0.936170 (-3125 2875);
PAINT GREEN (-3125 2875);
DISPLAY INVISIBLE (-3125 2875);
FORCEADD PVDDQ_GHJ..1
(-1350 2500);
FORCEPROP 3 LASTPIN (-1350 2450) SIG_NAME PVDDQ_GHJ\g
J 0
(-1340 2460);
DISPLAY 0.659574 (-1340 2460);
PAINT MONO (-1340 2460);
DISPLAY INVISIBLE (-1340 2460);
FORCEPROP 1 LAST VOLTAGE 1.2V
J 0
(-1395 2457);
DISPLAY 0.340426 (-1395 2457);
PAINT SKYBLUE (-1395 2457);
DISPLAY INVISIBLE (-1395 2457);
FORCEPROP 2 LAST BOM_COST MEM
J 0
(-1350 2505);
PAINT ORANGE (-1350 2505);
DISPLAY INVISIBLE (-1350 2505);
FORCEPROP 2 LAST CDS_LIB mstr_symbols
J 0
(-1350 2500);
PAINT ORANGE (-1350 2500);
DISPLAY INVISIBLE (-1350 2500);
FORCEPROP 1 LAST BODY_TYPE PLUMBING
J 0
(-1395 2457);
DISPLAY 0.340426 (-1395 2457);
PAINT GREEN (-1395 2457);
DISPLAY INVISIBLE (-1395 2457);
FORCEPROP 1 LAST PATH I16
J 0
(-1300 2525);
DISPLAY 0.872340 (-1300 2525);
PAINT AQUA (-1300 2525);
DISPLAY INVISIBLE (-1300 2525);
FORCEPROP 2 LAST ROOM DDR4_CH_G
J 0
(-1350 2600);
DISPLAY 0.787234 (-1350 2600);
PAINT ORANGE (-1350 2600);
DISPLAY INVISIBLE (-1350 2600);
FORCEPROP 1 LAST HDL_POWER PVDDQ_GHJ
J 1
(-1350 2550);
DISPLAY 0.872340 (-1350 2550);
PAINT GREEN (-1350 2550);
DISPLAY INVISIBLE (-1350 2550);
FORCEADD TAP..6
(-3125 2825);
FORCEPROP 3 LASTPIN (-3075 2825) SIG_NAME M_G_CS_N<1>
J 0
(-3065 2835);
DISPLAY 0.659574 (-3065 2835);
PAINT MONO (-3065 2835);
DISPLAY INVISIBLE (-3065 2835);
FORCEPROP 1 LASTPIN (-3075 2825) BN 1
J 0
(-3125 2835);
DISPLAY 0.617021 (-3125 2835);
PAINT PINK (-3125 2835);
FORCEPROP 2 LAST CDS_LIB mstr_standard
J 0
(-3125 2825);
DISPLAY 0.787234 (-3125 2825);
PAINT MONO (-3125 2825);
DISPLAY INVISIBLE (-3125 2825);
FORCEPROP 1 LAST BODY_TYPE PLUMBING
J 0
(-3125 2775);
DISPLAY 1.234043 (-3125 2775);
PAINT GREEN (-3125 2775);
DISPLAY INVISIBLE (-3125 2775);
FORCEPROP 1 LAST HDL_TAP TRUE
J 0
(-2800 2700);
DISPLAY 1.234043 (-2800 2700);
PAINT GREEN (-2800 2700);
DISPLAY INVISIBLE (-2800 2700);
FORCEPROP 1 LAST PATH I160
J 0
(-3125 2825);
DISPLAY 0.936170 (-3125 2825);
PAINT GREEN (-3125 2825);
DISPLAY INVISIBLE (-3125 2825);
FORCEADD TAP..6
(-3125 2775);
FORCEPROP 3 LASTPIN (-3075 2775) SIG_NAME M_G_CS_N<0>
J 0
(-3065 2785);
DISPLAY 0.659574 (-3065 2785);
PAINT MONO (-3065 2785);
DISPLAY INVISIBLE (-3065 2785);
FORCEPROP 1 LASTPIN (-3075 2775) BN 0
J 0
(-3125 2785);
DISPLAY 0.617021 (-3125 2785);
PAINT PINK (-3125 2785);
FORCEPROP 2 LAST CDS_LIB mstr_standard
J 0
(-3125 2775);
DISPLAY 0.787234 (-3125 2775);
PAINT MONO (-3125 2775);
DISPLAY INVISIBLE (-3125 2775);
FORCEPROP 1 LAST BODY_TYPE PLUMBING
J 0
(-3125 2725);
DISPLAY 1.234043 (-3125 2725);
PAINT GREEN (-3125 2725);
DISPLAY INVISIBLE (-3125 2725);
FORCEPROP 1 LAST HDL_TAP TRUE
J 0
(-2800 2650);
DISPLAY 1.234043 (-2800 2650);
PAINT GREEN (-2800 2650);
DISPLAY INVISIBLE (-2800 2650);
FORCEPROP 1 LAST PATH I161
J 0
(-3125 2775);
DISPLAY 0.936170 (-3125 2775);
PAINT GREEN (-3125 2775);
DISPLAY INVISIBLE (-3125 2775);
FORCEADD TAP..6
(-3125 2675);
FORCEPROP 3 LASTPIN (-3075 2675) SIG_NAME M_G_CKE<1>
J 0
(-3065 2685);
DISPLAY 0.659574 (-3065 2685);
PAINT MONO (-3065 2685);
DISPLAY INVISIBLE (-3065 2685);
FORCEPROP 1 LASTPIN (-3075 2675) BN 1
J 0
(-3125 2685);
DISPLAY 0.617021 (-3125 2685);
PAINT PINK (-3125 2685);
FORCEPROP 2 LAST CDS_LIB mstr_standard
J 0
(-3125 2675);
DISPLAY 0.787234 (-3125 2675);
PAINT MONO (-3125 2675);
DISPLAY INVISIBLE (-3125 2675);
FORCEPROP 1 LAST BODY_TYPE PLUMBING
J 0
(-3125 2625);
DISPLAY 1.234043 (-3125 2625);
PAINT GREEN (-3125 2625);
DISPLAY INVISIBLE (-3125 2625);
FORCEPROP 1 LAST HDL_TAP TRUE
J 0
(-2800 2550);
DISPLAY 1.234043 (-2800 2550);
PAINT GREEN (-2800 2550);
DISPLAY INVISIBLE (-2800 2550);
FORCEPROP 1 LAST PATH I162
J 0
(-3125 2675);
DISPLAY 0.936170 (-3125 2675);
PAINT GREEN (-3125 2675);
DISPLAY INVISIBLE (-3125 2675);
FORCEADD OFFPAGE..1
(-3775 2975);
FORCEPROP 2 LAST $XR1 78 
J 0
(-4086 2975);
DISPLAY 0.638298 (-4086 2975);
PAINT MONO (-4086 2975);
FORCEPROP 2 LAST $XR0 57 
J 0
(-3996 2975);
DISPLAY 0.638298 (-3996 2975);
PAINT MONO (-3996 2975);
FORCEPROP 2 LAST CDS_LIB mstr_standard
J 0
(-3775 2975);
DISPLAY 0.787234 (-3775 2975);
PAINT MONO (-3775 2975);
DISPLAY INVISIBLE (-3775 2975);
FORCEPROP 1 LAST OFFPAGE TRUE
J 0
(-3450 2850);
DISPLAY 0.936170 (-3450 2850);
PAINT GREEN (-3450 2850);
DISPLAY INVISIBLE (-3450 2850);
FORCEPROP 1 LAST COMMENT_BODY TRUE
J 0
(-3650 2875);
DISPLAY 0.936170 (-3650 2875);
PAINT GREEN (-3650 2875);
DISPLAY INVISIBLE (-3650 2875);
FORCEPROP 2 LAST PATH I163
J 0
(-3725 3050);
DISPLAY 0.787234 (-3725 3050);
PAINT MONO (-3725 3050);
DISPLAY INVISIBLE (-3725 3050);
FORCEADD OFFPAGE..1
(-3775 2725);
FORCEPROP 2 LAST $XR1 78 
J 0
(-4086 2725);
DISPLAY 0.638298 (-4086 2725);
PAINT MONO (-4086 2725);
FORCEPROP 2 LAST $XR0 57 
J 0
(-3996 2725);
DISPLAY 0.638298 (-3996 2725);
PAINT MONO (-3996 2725);
FORCEPROP 2 LAST CDS_LIB mstr_standard
J 0
(-3775 2725);
DISPLAY 0.787234 (-3775 2725);
PAINT MONO (-3775 2725);
DISPLAY INVISIBLE (-3775 2725);
FORCEPROP 1 LAST OFFPAGE TRUE
J 0
(-3450 2600);
DISPLAY 0.936170 (-3450 2600);
PAINT GREEN (-3450 2600);
DISPLAY INVISIBLE (-3450 2600);
FORCEPROP 1 LAST COMMENT_BODY TRUE
J 0
(-3650 2625);
DISPLAY 0.936170 (-3650 2625);
PAINT GREEN (-3650 2625);
DISPLAY INVISIBLE (-3650 2625);
FORCEPROP 2 LAST PATH I164
J 0
(-3725 2800);
DISPLAY 0.787234 (-3725 2800);
PAINT MONO (-3725 2800);
DISPLAY INVISIBLE (-3725 2800);
FORCEADD TAP..6
(-3125 2625);
FORCEPROP 3 LASTPIN (-3075 2625) SIG_NAME M_G_CKE<0>
J 0
(-3065 2635);
DISPLAY 0.659574 (-3065 2635);
PAINT MONO (-3065 2635);
DISPLAY INVISIBLE (-3065 2635);
FORCEPROP 1 LASTPIN (-3075 2625) BN 0
J 0
(-3125 2635);
DISPLAY 0.617021 (-3125 2635);
PAINT PINK (-3125 2635);
FORCEPROP 2 LAST CDS_LIB mstr_standard
J 0
(-3125 2625);
DISPLAY 0.787234 (-3125 2625);
PAINT MONO (-3125 2625);
DISPLAY INVISIBLE (-3125 2625);
FORCEPROP 1 LAST BODY_TYPE PLUMBING
J 0
(-3125 2575);
DISPLAY 1.234043 (-3125 2575);
PAINT GREEN (-3125 2575);
DISPLAY INVISIBLE (-3125 2575);
FORCEPROP 1 LAST HDL_TAP TRUE
J 0
(-2800 2500);
DISPLAY 1.234043 (-2800 2500);
PAINT GREEN (-2800 2500);
DISPLAY INVISIBLE (-2800 2500);
FORCEPROP 1 LAST PATH I165
J 0
(-3125 2625);
DISPLAY 0.936170 (-3125 2625);
PAINT GREEN (-3125 2625);
DISPLAY INVISIBLE (-3125 2625);
FORCEADD TAP..6
(-3125 2525);
FORCEPROP 3 LASTPIN (-3075 2525) SIG_NAME M_G_ODT<1>
J 0
(-3065 2535);
DISPLAY 0.659574 (-3065 2535);
PAINT MONO (-3065 2535);
DISPLAY INVISIBLE (-3065 2535);
FORCEPROP 1 LASTPIN (-3075 2525) BN 1
J 0
(-3125 2535);
DISPLAY 0.617021 (-3125 2535);
PAINT PINK (-3125 2535);
FORCEPROP 2 LAST CDS_LIB mstr_standard
J 0
(-3125 2525);
DISPLAY 0.787234 (-3125 2525);
PAINT MONO (-3125 2525);
DISPLAY INVISIBLE (-3125 2525);
FORCEPROP 1 LAST BODY_TYPE PLUMBING
J 0
(-3125 2475);
DISPLAY 1.234043 (-3125 2475);
PAINT GREEN (-3125 2475);
DISPLAY INVISIBLE (-3125 2475);
FORCEPROP 1 LAST HDL_TAP TRUE
J 0
(-2800 2400);
DISPLAY 1.234043 (-2800 2400);
PAINT GREEN (-2800 2400);
DISPLAY INVISIBLE (-2800 2400);
FORCEPROP 1 LAST PATH I166
J 0
(-3125 2525);
DISPLAY 0.936170 (-3125 2525);
PAINT GREEN (-3125 2525);
DISPLAY INVISIBLE (-3125 2525);
FORCEADD OFFPAGE..1
(-3775 2575);
FORCEPROP 2 LAST $XR1 78 
J 0
(-4086 2575);
DISPLAY 0.638298 (-4086 2575);
PAINT MONO (-4086 2575);
FORCEPROP 2 LAST $XR0 57 
J 0
(-3996 2575);
DISPLAY 0.638298 (-3996 2575);
PAINT MONO (-3996 2575);
FORCEPROP 2 LAST CDS_LIB mstr_standard
J 0
(-3775 2575);
DISPLAY 0.787234 (-3775 2575);
PAINT MONO (-3775 2575);
DISPLAY INVISIBLE (-3775 2575);
FORCEPROP 1 LAST OFFPAGE TRUE
J 0
(-3450 2450);
DISPLAY 0.936170 (-3450 2450);
PAINT GREEN (-3450 2450);
DISPLAY INVISIBLE (-3450 2450);
FORCEPROP 1 LAST COMMENT_BODY TRUE
J 0
(-3650 2475);
DISPLAY 0.936170 (-3650 2475);
PAINT GREEN (-3650 2475);
DISPLAY INVISIBLE (-3650 2475);
FORCEPROP 2 LAST PATH I167
J 0
(-3725 2650);
DISPLAY 0.787234 (-3725 2650);
PAINT MONO (-3725 2650);
DISPLAY INVISIBLE (-3725 2650);
FORCEADD TAP..6
(-3125 2475);
FORCEPROP 3 LASTPIN (-3075 2475) SIG_NAME M_G_ODT<0>
J 0
(-3065 2485);
DISPLAY 0.659574 (-3065 2485);
PAINT MONO (-3065 2485);
DISPLAY INVISIBLE (-3065 2485);
FORCEPROP 1 LASTPIN (-3075 2475) BN 0
J 0
(-3125 2485);
DISPLAY 0.617021 (-3125 2485);
PAINT PINK (-3125 2485);
FORCEPROP 2 LAST CDS_LIB mstr_standard
J 0
(-3125 2475);
DISPLAY 0.787234 (-3125 2475);
PAINT MONO (-3125 2475);
DISPLAY INVISIBLE (-3125 2475);
FORCEPROP 1 LAST BODY_TYPE PLUMBING
J 0
(-3125 2425);
DISPLAY 1.234043 (-3125 2425);
PAINT GREEN (-3125 2425);
DISPLAY INVISIBLE (-3125 2425);
FORCEPROP 1 LAST HDL_TAP TRUE
J 0
(-2800 2350);
DISPLAY 1.234043 (-2800 2350);
PAINT GREEN (-2800 2350);
DISPLAY INVISIBLE (-2800 2350);
FORCEPROP 1 LAST PATH I168
J 0
(-3125 2475);
DISPLAY 0.936170 (-3125 2475);
PAINT GREEN (-3125 2475);
DISPLAY INVISIBLE (-3125 2475);
FORCEADD PVTT_GHJ..1
(-1150 2650);
FORCEPROP 3 LASTPIN (-1150 2600) SIG_NAME PVTT_GHJ\g
J 0
(-1140 2610);
DISPLAY 0.659574 (-1140 2610);
PAINT MONO (-1140 2610);
DISPLAY INVISIBLE (-1140 2610);
FORCEPROP 1 LAST VOLTAGE 0.6V
J 0
(-1195 2607);
DISPLAY 0.340426 (-1195 2607);
PAINT SKYBLUE (-1195 2607);
DISPLAY INVISIBLE (-1195 2607);
FORCEPROP 2 LAST BOM_COST MEM
J 0
(-1150 2655);
PAINT ORANGE (-1150 2655);
DISPLAY INVISIBLE (-1150 2655);
FORCEPROP 2 LAST CDS_LIB mstr_symbols
J 0
(-1150 2650);
PAINT ORANGE (-1150 2650);
DISPLAY INVISIBLE (-1150 2650);
FORCEPROP 1 LAST BODY_TYPE PLUMBING
J 0
(-1195 2607);
DISPLAY 0.340426 (-1195 2607);
PAINT GREEN (-1195 2607);
DISPLAY INVISIBLE (-1195 2607);
FORCEPROP 1 LAST PATH I17
J 0
(-1100 2675);
DISPLAY 0.872340 (-1100 2675);
PAINT AQUA (-1100 2675);
DISPLAY INVISIBLE (-1100 2675);
FORCEPROP 2 LAST ROOM DDR4_CH_G
J 0
(-1150 2750);
DISPLAY 0.787234 (-1150 2750);
PAINT ORANGE (-1150 2750);
DISPLAY INVISIBLE (-1150 2750);
FORCEPROP 1 LAST HDL_POWER PVTT_GHJ
J 1
(-1150 2700);
DISPLAY 0.872340 (-1150 2700);
PAINT GREEN (-1150 2700);
DISPLAY INVISIBLE (-1150 2700);
FORCEADD SCONN288_H44441004..4
(-300 1950);
FORCEPROP 2 LASTPIN (-800 1300) $PN 226
J 2
(-810 1310);
DISPLAY 0.617021 (-810 1310);
PAINT ORANGE (-810 1310);
FORCEPROP 1 LAST LOCATION J1G1
J 0
(-750 3050);
DISPLAY 0.617021 (-750 3050);
PAINT AQUA (-750 3050);
FORCEPROP 1 LAST PART_NUMBER H44441-004
J 0
(-750 900);
DISPLAY 0.617021 (-750 900);
PAINT BLUE (-750 900);
FORCEPROP 1 LAST MATERIAL SCONN
J 0
(-750 3000);
DISPLAY 0.617021 (-750 3000);
PAINT SKYBLUE (-750 3000);
FORCEPROP 2 LASTPIN (-800 2500) $PN 77
J 2
(-810 2510);
DISPLAY 0.617021 (-810 2510);
PAINT ORANGE (-810 2510);
FORCEPROP 2 LASTPIN (-800 2450) $PN 221
J 2
(-810 2460);
DISPLAY 0.617021 (-810 2460);
PAINT ORANGE (-810 2460);
FORCEPROP 2 LASTPIN (-800 2800) $PN 142
J 2
(-810 2810);
DISPLAY 0.617021 (-810 2810);
PAINT ORANGE (-810 2810);
FORCEPROP 2 LASTPIN (-800 2750) $PN 143
J 2
(-810 2760);
DISPLAY 0.617021 (-810 2760);
PAINT ORANGE (-810 2760);
FORCEPROP 2 LASTPIN (-800 2700) $PN 288
J 2
(-810 2710);
DISPLAY 0.617021 (-810 2710);
PAINT ORANGE (-810 2710);
FORCEPROP 2 LASTPIN (-800 2650) $PN 286
J 2
(-810 2660);
DISPLAY 0.617021 (-810 2660);
PAINT ORANGE (-810 2660);
FORCEPROP 2 LASTPIN (-800 2350) $PN 59
J 2
(-810 2360);
DISPLAY 0.617021 (-810 2360);
PAINT ORANGE (-810 2360);
FORCEPROP 2 LASTPIN (-800 2300) $PN 61
J 2
(-810 2310);
DISPLAY 0.617021 (-810 2310);
PAINT ORANGE (-810 2310);
FORCEPROP 2 LASTPIN (-800 2250) $PN 64
J 2
(-810 2260);
DISPLAY 0.617021 (-810 2260);
PAINT ORANGE (-810 2260);
FORCEPROP 2 LASTPIN (-800 2200) $PN 67
J 2
(-810 2210);
DISPLAY 0.617021 (-810 2210);
PAINT ORANGE (-810 2210);
FORCEPROP 2 LASTPIN (-800 2150) $PN 70
J 2
(-810 2160);
DISPLAY 0.617021 (-810 2160);
PAINT ORANGE (-810 2160);
FORCEPROP 2 LASTPIN (-800 2100) $PN 73
J 2
(-810 2110);
DISPLAY 0.617021 (-810 2110);
PAINT ORANGE (-810 2110);
FORCEPROP 2 LASTPIN (-800 2050) $PN 76
J 2
(-810 2060);
DISPLAY 0.617021 (-810 2060);
PAINT ORANGE (-810 2060);
FORCEPROP 2 LASTPIN (-800 2000) $PN 80
J 2
(-810 2010);
DISPLAY 0.617021 (-810 2010);
PAINT ORANGE (-810 2010);
FORCEPROP 2 LASTPIN (-800 1950) $PN 83
J 2
(-810 1960);
DISPLAY 0.617021 (-810 1960);
PAINT ORANGE (-810 1960);
FORCEPROP 2 LASTPIN (-800 1900) $PN 85
J 2
(-810 1910);
DISPLAY 0.617021 (-810 1910);
PAINT ORANGE (-810 1910);
FORCEPROP 2 LASTPIN (-800 1850) $PN 88
J 2
(-810 1860);
DISPLAY 0.617021 (-810 1860);
PAINT ORANGE (-810 1860);
FORCEPROP 2 LASTPIN (-800 1800) $PN 90
J 2
(-810 1810);
DISPLAY 0.617021 (-810 1810);
PAINT ORANGE (-810 1810);
FORCEPROP 2 LASTPIN (-800 1750) $PN 92
J 2
(-810 1760);
DISPLAY 0.617021 (-810 1760);
PAINT ORANGE (-810 1760);
FORCEPROP 2 LASTPIN (-800 1700) $PN 204
J 2
(-810 1710);
DISPLAY 0.617021 (-810 1710);
PAINT ORANGE (-810 1710);
FORCEPROP 2 LASTPIN (-800 1650) $PN 206
J 2
(-810 1660);
DISPLAY 0.617021 (-810 1660);
PAINT ORANGE (-810 1660);
FORCEPROP 2 LASTPIN (-800 1600) $PN 209
J 2
(-810 1610);
DISPLAY 0.617021 (-810 1610);
PAINT ORANGE (-810 1610);
FORCEPROP 2 LASTPIN (-800 1550) $PN 212
J 2
(-810 1560);
DISPLAY 0.617021 (-810 1560);
PAINT ORANGE (-810 1560);
FORCEPROP 2 LASTPIN (-800 1500) $PN 215
J 2
(-810 1510);
DISPLAY 0.617021 (-810 1510);
PAINT ORANGE (-810 1510);
FORCEPROP 2 LASTPIN (-800 1450) $PN 217
J 2
(-810 1460);
DISPLAY 0.617021 (-810 1460);
PAINT ORANGE (-810 1460);
FORCEPROP 2 LASTPIN (-800 1400) $PN 220
J 2
(-810 1410);
DISPLAY 0.617021 (-810 1410);
PAINT ORANGE (-810 1410);
FORCEPROP 2 LASTPIN (-800 1350) $PN 223
J 2
(-810 1360);
DISPLAY 0.617021 (-810 1360);
PAINT ORANGE (-810 1360);
FORCEPROP 2 LASTPIN (-800 1250) $PN 229
J 2
(-810 1260);
DISPLAY 0.617021 (-810 1260);
PAINT ORANGE (-810 1260);
FORCEPROP 2 LASTPIN (-800 1200) $PN 231
J 2
(-810 1210);
DISPLAY 0.617021 (-810 1210);
PAINT ORANGE (-810 1210);
FORCEPROP 2 LASTPIN (-800 1150) $PN 233
J 2
(-810 1160);
DISPLAY 0.617021 (-810 1160);
PAINT ORANGE (-810 1160);
FORCEPROP 2 LASTPIN (-800 1100) $PN 236
J 2
(-810 1110);
DISPLAY 0.617021 (-810 1110);
PAINT ORANGE (-810 1110);
FORCEPROP 2 LASTPIN (200 2800) $PN 1
J 0
(210 2810);
DISPLAY 0.617021 (210 2810);
PAINT ORANGE (210 2810);
FORCEPROP 2 LASTPIN (200 2750) $PN 145
J 0
(210 2760);
DISPLAY 0.617021 (210 2760);
PAINT ORANGE (210 2760);
FORCEPROP 2 LASTPIN (-800 2600) $PN 287
J 2
(-810 2610);
DISPLAY 0.617021 (-810 2610);
PAINT ORANGE (-810 2610);
FORCEPROP 1 LAST PACK_TYPE PIP
J 0
(-750 3100);
PAINT SKYBLUE (-750 3100);
DISPLAY INVISIBLE (-750 3100);
FORCEPROP 2 LAST BOM_COST MEM
J 0
(-300 1950);
PAINT ORANGE (-300 1950);
DISPLAY INVISIBLE (-300 1950);
FORCEPROP 2 LAST CDS_LIB mstr_sconn
J 0
(-300 1950);
PAINT ORANGE (-300 1950);
DISPLAY INVISIBLE (-300 1950);
FORCEPROP 2 LAST SEC_TYPE PIP
J 0
(-750 3100);
DISPLAY 1.021277 (-750 3100);
PAINT ORANGE (-750 3100);
DISPLAY INVISIBLE (-750 3100);
FORCEPROP 2 LAST SEC 4
J 0
(-750 3100);
DISPLAY 0.680851 (-750 3100);
PAINT MONO (-750 3100);
DISPLAY INVISIBLE (-750 3100);
FORCEPROP 2 LAST CDS_LOCATION J1G1
J 0
(-750 3050);
DISPLAY 0.617021 (-750 3050);
PAINT AQUA (-750 3050);
DISPLAY INVISIBLE (-750 3050);
FORCEPROP 1 LAST PATH I171
J 0
(-300 3000);
PAINT GREEN (-300 3000);
DISPLAY INVISIBLE (-300 3000);
FORCEPROP 2 LAST ROOM DDR4_CH_G
J 0
(-300 1950);
PAINT ORANGE (-300 1950);
DISPLAY INVISIBLE (-300 1950);
FORCEADD GND..1
R 2
(2500 900);
FORCEPROP 3 LASTPIN (2500 950) SIG_NAME GND\g
J 0
(2510 960);
DISPLAY 0.659574 (2510 960);
PAINT MONO (2510 960);
DISPLAY INVISIBLE (2510 960);
FORCEPROP 1 LAST VOLTAGE 0
J 0
(2500 900);
PAINT SKYBLUE (2500 900);
DISPLAY INVISIBLE (2500 900);
FORCEPROP 1 LAST SIZE 1B
J 2
(2425 850);
DISPLAY 1.170213 (2425 850);
PAINT GREEN (2425 850);
DISPLAY INVISIBLE (2425 850);
FORCEPROP 2 LAST CDS_LIB mstr_symbols
J 0
(2500 900);
DISPLAY 0.787234 (2500 900);
PAINT MONO (2500 900);
DISPLAY INVISIBLE (2500 900);
FORCEPROP 2 LAST BOM_COST MEM
J 0
(2500 905);
PAINT ORANGE (2500 905);
DISPLAY INVISIBLE (2500 905);
FORCEPROP 1 LAST BODY_TYPE PLUMBING
J 2
(2545 857);
DISPLAY 0.340426 (2545 857);
PAINT GREEN (2545 857);
DISPLAY INVISIBLE (2545 857);
FORCEPROP 1 LAST PATH I172
J 2
(2425 900);
DISPLAY 1.404255 (2425 900);
PAINT GREEN (2425 900);
DISPLAY INVISIBLE (2425 900);
FORCEPROP 2 LAST ROOM DDR4_CH_G
J 0
(2500 905);
PAINT ORANGE (2500 905);
DISPLAY INVISIBLE (2500 905);
FORCEPROP 1 LAST HDL_POWER GND
J 2
(2500 1050);
DISPLAY 0.553191 (2500 1050);
PAINT GREEN (2500 1050);
DISPLAY INVISIBLE (2500 1050);
FORCEADD OFFPAGE..6
(-3775 1425);
FORCEPROP 2 LASTPIN (-3725 1425) SIG_NAME SMB_DDR_GHJ_VPP_SDA
J 0
(-3685 1435);
DISPLAY 0.617021 (-3685 1435);
PAINT ORANGE (-3685 1435);
FORCEPROP 2 LAST $XR5 99 
J 0
(-4474 1425);
DISPLAY 0.638298 (-4474 1425);
PAINT MONO (-4474 1425);
FORCEPROP 2 LAST $XR4 82 
J 0
(-4384 1425);
DISPLAY 0.638298 (-4384 1425);
PAINT MONO (-4384 1425);
FORCEPROP 2 LAST $XR3 81 
J 0
(-4294 1425);
DISPLAY 0.638298 (-4294 1425);
PAINT MONO (-4294 1425);
FORCEPROP 2 LAST $XR2 80 
J 0
(-4204 1425);
DISPLAY 0.638298 (-4204 1425);
PAINT MONO (-4204 1425);
FORCEPROP 2 LAST $XR1 79 
J 0
(-4114 1425);
DISPLAY 0.638298 (-4114 1425);
PAINT MONO (-4114 1425);
FORCEPROP 2 LAST $XR0 78 
J 0
(-4024 1425);
DISPLAY 0.638298 (-4024 1425);
PAINT MONO (-4024 1425);
FORCEPROP 2 LAST CDS_LIB mstr_standard
J 0
(-3775 1425);
DISPLAY 0.787234 (-3775 1425);
PAINT MONO (-3775 1425);
DISPLAY INVISIBLE (-3775 1425);
FORCEPROP 1 LAST OFFPAGE TRUE
J 0
(-3450 1300);
DISPLAY 0.936170 (-3450 1300);
PAINT GREEN (-3450 1300);
DISPLAY INVISIBLE (-3450 1300);
FORCEPROP 1 LAST COMMENT_BODY TRUE
J 0
(-3675 1350);
DISPLAY 0.936170 (-3675 1350);
PAINT GREEN (-3675 1350);
DISPLAY INVISIBLE (-3675 1350);
FORCEPROP 2 LAST PATH I173
J 0
(-4100 1475);
DISPLAY 0.787234 (-4100 1475);
PAINT ORANGE (-4100 1475);
DISPLAY INVISIBLE (-4100 1475);
FORCEADD OFFPAGE..1
(-3775 1375);
FORCEPROP 2 LAST $XR5 82 
J 0
(-4476 1375);
DISPLAY 0.638298 (-4476 1375);
PAINT MONO (-4476 1375);
FORCEPROP 2 LAST $XR4 81 
J 0
(-4386 1375);
DISPLAY 0.638298 (-4386 1375);
PAINT MONO (-4386 1375);
FORCEPROP 2 LAST $XR3 80 
J 0
(-4296 1375);
DISPLAY 0.638298 (-4296 1375);
PAINT MONO (-4296 1375);
FORCEPROP 2 LAST $XR2 79 
J 0
(-4206 1375);
DISPLAY 0.638298 (-4206 1375);
PAINT MONO (-4206 1375);
FORCEPROP 2 LAST $XR1 78 
J 0
(-4116 1375);
DISPLAY 0.638298 (-4116 1375);
PAINT MONO (-4116 1375);
FORCEPROP 2 LAST $XR0 99 
J 0
(-4026 1375);
DISPLAY 0.638298 (-4026 1375);
PAINT MONO (-4026 1375);
FORCEPROP 2 LAST CDS_LIB mstr_standard
J 0
(-3775 1375);
DISPLAY 0.787234 (-3775 1375);
PAINT MONO (-3775 1375);
DISPLAY INVISIBLE (-3775 1375);
FORCEPROP 1 LAST OFFPAGE TRUE
J 0
(-3450 1250);
DISPLAY 0.936170 (-3450 1250);
PAINT GREEN (-3450 1250);
DISPLAY INVISIBLE (-3450 1250);
FORCEPROP 1 LAST COMMENT_BODY TRUE
J 0
(-3650 1275);
DISPLAY 0.936170 (-3650 1275);
PAINT GREEN (-3650 1275);
DISPLAY INVISIBLE (-3650 1275);
FORCEPROP 2 LAST PATH I174
J 0
(-4050 1425);
DISPLAY 0.787234 (-4050 1425);
PAINT ORANGE (-4050 1425);
DISPLAY INVISIBLE (-4050 1425);
FORCEADD OFFPAGE..1
(-4575 1275);
FORCEPROP 2 LAST $XR1 78 
J 0
(-4917 1275);
DISPLAY 0.638298 (-4917 1275);
PAINT MONO (-4917 1275);
FORCEPROP 2 LAST $XR0 100 
J 0
(-4827 1275);
DISPLAY 0.638298 (-4827 1275);
PAINT MONO (-4827 1275);
FORCEPROP 2 LAST CDS_LIB mstr_standard
J 0
(-4575 1275);
DISPLAY 0.787234 (-4575 1275);
PAINT MONO (-4575 1275);
DISPLAY INVISIBLE (-4575 1275);
FORCEPROP 1 LAST OFFPAGE TRUE
J 0
(-4250 1150);
DISPLAY 0.936170 (-4250 1150);
PAINT GREEN (-4250 1150);
DISPLAY INVISIBLE (-4250 1150);
FORCEPROP 1 LAST COMMENT_BODY TRUE
J 0
(-4450 1175);
DISPLAY 0.936170 (-4450 1175);
PAINT GREEN (-4450 1175);
DISPLAY INVISIBLE (-4450 1175);
FORCEPROP 2 LAST PATH I175
J 0
(-4825 1325);
DISPLAY 0.787234 (-4825 1325);
PAINT ORANGE (-4825 1325);
DISPLAY INVISIBLE (-4825 1325);
FORCEADD GND..1
R 2
(-5075 1425);
FORCEPROP 3 LASTPIN (-5075 1475) SIG_NAME GND\g
J 0
(-5065 1485);
DISPLAY 0.659574 (-5065 1485);
PAINT MONO (-5065 1485);
DISPLAY INVISIBLE (-5065 1485);
FORCEPROP 1 LAST VOLTAGE 0
J 0
(-5075 1425);
PAINT SKYBLUE (-5075 1425);
DISPLAY INVISIBLE (-5075 1425);
FORCEPROP 1 LAST SIZE 1B
J 2
(-5150 1375);
DISPLAY 1.170213 (-5150 1375);
PAINT GREEN (-5150 1375);
DISPLAY INVISIBLE (-5150 1375);
FORCEPROP 2 LAST CDS_LIB mstr_symbols
J 0
(-5075 1425);
DISPLAY 0.787234 (-5075 1425);
PAINT MONO (-5075 1425);
DISPLAY INVISIBLE (-5075 1425);
FORCEPROP 2 LAST BOM_COST MEM
J 0
(-5075 1430);
PAINT ORANGE (-5075 1430);
DISPLAY INVISIBLE (-5075 1430);
FORCEPROP 1 LAST BODY_TYPE PLUMBING
J 2
(-5030 1382);
DISPLAY 0.340426 (-5030 1382);
PAINT GREEN (-5030 1382);
DISPLAY INVISIBLE (-5030 1382);
FORCEPROP 1 LAST PATH I177
J 2
(-5150 1425);
DISPLAY 1.404255 (-5150 1425);
PAINT GREEN (-5150 1425);
DISPLAY INVISIBLE (-5150 1425);
FORCEPROP 2 LAST ROOM DDR4_CH_G
J 0
(-5075 1430);
PAINT ORANGE (-5075 1430);
DISPLAY INVISIBLE (-5075 1430);
FORCEPROP 1 LAST HDL_POWER GND
J 2
(-5075 1575);
DISPLAY 0.553191 (-5075 1575);
PAINT GREEN (-5075 1575);
DISPLAY INVISIBLE (-5075 1575);
FORCEADD OFFPAGE..5
(-4100 2075);
FORCEPROP 2 LAST $XR23 94 
J 0
(-4594 2111);
DISPLAY 0.638298 (-4594 2111);
PAINT MONO (-4594 2111);
FORCEPROP 2 LAST $XR22 88 
J 0
(-4504 2111);
DISPLAY 0.638298 (-4504 2111);
PAINT MONO (-4504 2111);
FORCEPROP 2 LAST $XR21 87 
J 0
(-4414 2111);
DISPLAY 0.638298 (-4414 2111);
PAINT MONO (-4414 2111);
FORCEPROP 2 LAST $XR20 86 
J 0
(-4324 2111);
DISPLAY 0.638298 (-4324 2111);
PAINT MONO (-4324 2111);
FORCEPROP 2 LAST $XR19 85 
J 0
(-5134 2039);
DISPLAY 0.638298 (-5134 2039);
PAINT MONO (-5134 2039);
FORCEPROP 2 LAST $XR18 84 
J 0
(-5044 2039);
DISPLAY 0.638298 (-5044 2039);
PAINT MONO (-5044 2039);
FORCEPROP 2 LAST $XR17 83 
J 0
(-4954 2039);
DISPLAY 0.638298 (-4954 2039);
PAINT MONO (-4954 2039);
FORCEPROP 2 LAST $XR16 82 
J 0
(-4864 2039);
DISPLAY 0.638298 (-4864 2039);
PAINT MONO (-4864 2039);
FORCEPROP 2 LAST $XR15 81 
J 0
(-4774 2039);
DISPLAY 0.638298 (-4774 2039);
PAINT MONO (-4774 2039);
FORCEPROP 2 LAST $XR14 80 
J 0
(-4684 2039);
DISPLAY 0.638298 (-4684 2039);
PAINT MONO (-4684 2039);
FORCEPROP 2 LAST $XR13 79 
J 0
(-4594 2039);
DISPLAY 0.638298 (-4594 2039);
PAINT MONO (-4594 2039);
FORCEPROP 2 LAST $XR12 78 
J 0
(-4504 2039);
DISPLAY 0.638298 (-4504 2039);
PAINT MONO (-4504 2039);
FORCEPROP 2 LAST $XR11 54 
J 0
(-4414 2039);
DISPLAY 0.638298 (-4414 2039);
PAINT MONO (-4414 2039);
FORCEPROP 2 LAST $XR10 53 
J 0
(-4324 2039);
DISPLAY 0.638298 (-4324 2039);
PAINT MONO (-4324 2039);
FORCEPROP 2 LAST $XR9 52 
J 0
(-5134 2075);
DISPLAY 0.638298 (-5134 2075);
PAINT MONO (-5134 2075);
FORCEPROP 2 LAST $XR8 51 
J 0
(-5044 2075);
DISPLAY 0.638298 (-5044 2075);
PAINT MONO (-5044 2075);
FORCEPROP 2 LAST $XR7 50 
J 0
(-4954 2075);
DISPLAY 0.638298 (-4954 2075);
PAINT MONO (-4954 2075);
FORCEPROP 2 LAST $XR6 49 
J 0
(-4864 2075);
DISPLAY 0.638298 (-4864 2075);
PAINT MONO (-4864 2075);
FORCEPROP 2 LAST $XR5 48 
J 0
(-4774 2075);
DISPLAY 0.638298 (-4774 2075);
PAINT MONO (-4774 2075);
FORCEPROP 2 LAST $XR4 47 
J 0
(-4684 2075);
DISPLAY 0.638298 (-4684 2075);
PAINT MONO (-4684 2075);
FORCEPROP 2 LAST $XR3 46 
J 0
(-4594 2075);
DISPLAY 0.638298 (-4594 2075);
PAINT MONO (-4594 2075);
FORCEPROP 2 LAST $XR2 45 
J 0
(-4504 2075);
DISPLAY 0.638298 (-4504 2075);
PAINT MONO (-4504 2075);
FORCEPROP 2 LAST $XR1 44 
J 0
(-4414 2075);
DISPLAY 0.638298 (-4414 2075);
PAINT MONO (-4414 2075);
FORCEPROP 2 LAST $XR0 43 
J 0
(-4324 2075);
DISPLAY 0.638298 (-4324 2075);
PAINT MONO (-4324 2075);
FORCEPROP 2 LAST CDS_LIB mstr_standard
J 0
(-4100 2075);
DISPLAY 0.787234 (-4100 2075);
PAINT MONO (-4100 2075);
DISPLAY INVISIBLE (-4100 2075);
FORCEPROP 1 LAST OFFPAGE TRUE
J 0
(-3775 1950);
DISPLAY 1.404255 (-3775 1950);
PAINT GREEN (-3775 1950);
DISPLAY INVISIBLE (-3775 1950);
FORCEPROP 1 LAST COMMENT_BODY TRUE
J 0
(-4000 2000);
DISPLAY 1.404255 (-4000 2000);
PAINT GREEN (-4000 2000);
DISPLAY INVISIBLE (-4000 2000);
FORCEPROP 2 LAST PATH I178
J 0
(-4050 2150);
DISPLAY 0.787234 (-4050 2150);
PAINT ORANGE (-4050 2150);
DISPLAY INVISIBLE (-4050 2150);
FORCEADD OFFPAGE..1
(-3775 2375);
FORCEPROP 2 LAST $XR1 78 
J 0
(-4116 2375);
DISPLAY 0.638298 (-4116 2375);
PAINT MONO (-4116 2375);
FORCEPROP 2 LAST $XR0 57 
J 0
(-4026 2375);
DISPLAY 0.638298 (-4026 2375);
PAINT MONO (-4026 2375);
FORCEPROP 2 LAST CDS_LIB mstr_standard
J 0
(-3775 2375);
DISPLAY 0.787234 (-3775 2375);
PAINT MONO (-3775 2375);
DISPLAY INVISIBLE (-3775 2375);
FORCEPROP 1 LAST OFFPAGE TRUE
J 0
(-3450 2250);
DISPLAY 0.936170 (-3450 2250);
PAINT GREEN (-3450 2250);
DISPLAY INVISIBLE (-3450 2250);
FORCEPROP 1 LAST COMMENT_BODY TRUE
J 0
(-3650 2275);
DISPLAY 0.936170 (-3650 2275);
PAINT GREEN (-3650 2275);
DISPLAY INVISIBLE (-3650 2275);
FORCEPROP 2 LAST PATH I179
J 0
(-4025 2425);
PAINT ORANGE (-4025 2425);
DISPLAY INVISIBLE (-4025 2425);
FORCEADD GND..1
(-4425 825);
FORCEPROP 3 LASTPIN (-4425 875) SIG_NAME GND\g
J 0
(-4415 885);
DISPLAY 0.659574 (-4415 885);
PAINT MONO (-4415 885);
DISPLAY INVISIBLE (-4415 885);
FORCEPROP 1 LAST VOLTAGE 0
J 0
(-4425 825);
PAINT SKYBLUE (-4425 825);
DISPLAY INVISIBLE (-4425 825);
FORCEPROP 1 LAST SIZE 1B
J 0
(-4350 775);
DISPLAY 1.787234 (-4350 775);
PAINT GREEN (-4350 775);
DISPLAY INVISIBLE (-4350 775);
FORCEPROP 2 LAST CDS_LIB mstr_symbols
J 0
(-4425 825);
PAINT ORANGE (-4425 825);
DISPLAY INVISIBLE (-4425 825);
FORCEPROP 2 LAST BOM_COST MEM
J 0
(-4425 830);
PAINT ORANGE (-4425 830);
DISPLAY INVISIBLE (-4425 830);
FORCEPROP 1 LAST BODY_TYPE PLUMBING
J 0
(-4470 782);
DISPLAY 0.340426 (-4470 782);
PAINT GREEN (-4470 782);
DISPLAY INVISIBLE (-4470 782);
FORCEPROP 1 LAST PATH I180
J 0
(-4350 825);
DISPLAY 1.404255 (-4350 825);
PAINT GREEN (-4350 825);
DISPLAY INVISIBLE (-4350 825);
FORCEPROP 2 LAST ROOM DDR4_CH_G
J 0
(-4425 830);
PAINT ORANGE (-4425 830);
DISPLAY INVISIBLE (-4425 830);
FORCEPROP 1 LAST HDL_POWER GND
J 0
(-4425 975);
DISPLAY 1.404255 (-4425 975);
PAINT GREEN (-4425 975);
DISPLAY INVISIBLE (-4425 975);
FORCEADD CAP_A..1
R 2
(-4425 1075);
FORCEPROP 1 LAST LOCATION C1F22
J 2
(-4475 1175);
DISPLAY 0.617021 (-4475 1175);
PAINT AQUA (-4475 1175);
FORCEPROP 1 LAST PART_NUMBER A36096-045
J 2
(-4475 925);
DISPLAY 0.617021 (-4475 925);
PAINT BLUE (-4475 925);
FORCEPROP 1 LAST VALUE 0.01UF
J 2
(-4475 1125);
DISPLAY 0.617021 (-4475 1125);
PAINT SKYBLUE (-4475 1125);
FORCEPROP 1 LAST TOLERANCE 10%
J 2
(-4475 1025);
DISPLAY 0.617021 (-4475 1025);
PAINT SKYBLUE (-4475 1025);
FORCEPROP 1 LAST PACK_TYPE 0402V
J 2
(-4475 875);
DISPLAY 0.617021 (-4475 875);
PAINT SKYBLUE (-4475 875);
FORCEPROP 1 LAST VOLTAGE 25V
J 2
(-4475 1075);
DISPLAY 0.617021 (-4475 1075);
PAINT SKYBLUE (-4475 1075);
FORCEPROP 1 LAST MATERIAL X7R
J 2
(-4475 975);
DISPLAY 0.617021 (-4475 975);
PAINT SKYBLUE (-4475 975);
FORCEPROP 2 LAST CDS_LOCATION C1F22
J 2
(-4475 1175);
DISPLAY 0.617021 (-4475 1175);
PAINT AQUA (-4475 1175);
DISPLAY INVISIBLE (-4475 1175);
FORCEPROP 2 LAST BOM_COST MEM
J 0
(-4425 1075);
PAINT ORANGE (-4425 1075);
DISPLAY INVISIBLE (-4425 1075);
FORCEPROP 2 LAST CDS_LIB dev_discrete
J 0
(-4425 1075);
PAINT ORANGE (-4425 1075);
DISPLAY INVISIBLE (-4425 1075);
FORCEPROP 2 LAST CDS_SEC 1
J 2
(-4475 1275);
PAINT MONO (-4475 1275);
DISPLAY INVISIBLE (-4475 1275);
FORCEPROP 2 LAST $SEC 1
J 0
(-4475 1275);
PAINT MONO (-4475 1275);
DISPLAY INVISIBLE (-4475 1275);
FORCEPROP 1 LAST PATH I181
J 2
(-4475 1225);
DISPLAY 0.978723 (-4475 1225);
PAINT WHITE (-4475 1225);
DISPLAY INVISIBLE (-4475 1225);
FORCEPROP 2 LAST ROOM DDR4_CH_G
J 0
(-4425 1075);
PAINT ORANGE (-4425 1075);
DISPLAY INVISIBLE (-4425 1075);
FORCEPROP 1 LASTPIN (-4425 1175) $PN 1
J 2
(-4435 1155);
DISPLAY 0.787234 (-4435 1155);
PAINT ORANGE (-4435 1155);
DISPLAY INVISIBLE (-4435 1155);
FORCEPROP 1 LASTPIN (-4425 975) $PN 2
J 2
(-4435 955);
DISPLAY 0.787234 (-4435 955);
PAINT ORANGE (-4435 955);
DISPLAY INVISIBLE (-4435 955);
FORCEADD PVPP_GHJ..1
(-1000 2950);
FORCEPROP 3 LASTPIN (-1000 2900) SIG_NAME PVPP_GHJ\g
J 0
(-990 2910);
DISPLAY 0.659574 (-990 2910);
PAINT MONO (-990 2910);
DISPLAY INVISIBLE (-990 2910);
FORCEPROP 1 LAST VOLTAGE 2.5V
J 0
(-1045 2907);
DISPLAY 0.340426 (-1045 2907);
PAINT SKYBLUE (-1045 2907);
DISPLAY INVISIBLE (-1045 2907);
FORCEPROP 0 LAST BOM_COST MEM
J 0
(-1000 3050);
PAINT ORANGE (-1000 3050);
DISPLAY INVISIBLE (-1000 3050);
FORCEPROP 2 LAST CDS_LIB mstr_symbols
J 0
(-1000 2950);
PAINT ORANGE (-1000 2950);
DISPLAY INVISIBLE (-1000 2950);
FORCEPROP 1 LAST BODY_TYPE PLUMBING
J 0
(-1045 2907);
DISPLAY 0.340426 (-1045 2907);
PAINT GREEN (-1045 2907);
DISPLAY INVISIBLE (-1045 2907);
FORCEPROP 1 LAST PATH I182
J 0
(-950 2975);
DISPLAY 0.872340 (-950 2975);
PAINT AQUA (-950 2975);
DISPLAY INVISIBLE (-950 2975);
FORCEPROP 2 LAST ROOM DDR4_CH_G
J 0
(-1000 3050);
PAINT ORANGE (-1000 3050);
DISPLAY INVISIBLE (-1000 3050);
FORCEPROP 1 LAST HDL_POWER PVPP_GHJ
J 1
(-1000 3000);
DISPLAY 0.872340 (-1000 3000);
PAINT GREEN (-1000 3000);
DISPLAY INVISIBLE (-1000 3000);
FORCEADD PVPP_GHJ..1
(-5075 1775);
FORCEPROP 3 LASTPIN (-5075 1725) SIG_NAME PVPP_GHJ\g
J 0
(-5065 1735);
DISPLAY 0.659574 (-5065 1735);
PAINT MONO (-5065 1735);
DISPLAY INVISIBLE (-5065 1735);
FORCEPROP 1 LAST VOLTAGE 2.5V
J 0
(-5120 1732);
DISPLAY 0.340426 (-5120 1732);
PAINT SKYBLUE (-5120 1732);
DISPLAY INVISIBLE (-5120 1732);
FORCEPROP 0 LAST BOM_COST MEM
J 0
(-5075 1875);
PAINT ORANGE (-5075 1875);
DISPLAY INVISIBLE (-5075 1875);
FORCEPROP 2 LAST CDS_LIB mstr_symbols
J 0
(-5075 1775);
PAINT ORANGE (-5075 1775);
DISPLAY INVISIBLE (-5075 1775);
FORCEPROP 1 LAST BODY_TYPE PLUMBING
J 0
(-5120 1732);
DISPLAY 0.340426 (-5120 1732);
PAINT GREEN (-5120 1732);
DISPLAY INVISIBLE (-5120 1732);
FORCEPROP 1 LAST PATH I183
J 0
(-5025 1800);
DISPLAY 0.872340 (-5025 1800);
PAINT AQUA (-5025 1800);
DISPLAY INVISIBLE (-5025 1800);
FORCEPROP 2 LAST ROOM DDR4_CH_H
J 0
(-5075 1875);
PAINT ORANGE (-5075 1875);
DISPLAY INVISIBLE (-5075 1875);
FORCEPROP 1 LAST HDL_POWER PVPP_GHJ
J 1
(-5075 1825);
DISPLAY 0.872340 (-5075 1825);
PAINT GREEN (-5075 1825);
DISPLAY INVISIBLE (-5075 1825);
FORCEADD OFFPAGE..1
(-3775 975);
FORCEPROP 2 LAST $XR5 82 
J 0
(-3996 939);
DISPLAY 0.638298 (-3996 939);
PAINT MONO (-3996 939);
FORCEPROP 2 LAST $XR4 81 
J 0
(-4356 975);
DISPLAY 0.638298 (-4356 975);
PAINT MONO (-4356 975);
FORCEPROP 2 LAST $XR3 80 
J 0
(-4266 975);
DISPLAY 0.638298 (-4266 975);
PAINT MONO (-4266 975);
FORCEPROP 2 LAST $XR2 79 
J 0
(-4176 975);
DISPLAY 0.638298 (-4176 975);
PAINT MONO (-4176 975);
FORCEPROP 2 LAST $XR1 78 
J 0
(-4086 975);
DISPLAY 0.638298 (-4086 975);
PAINT MONO (-4086 975);
FORCEPROP 2 LAST $XR0 89 
J 0
(-3996 975);
DISPLAY 0.638298 (-3996 975);
PAINT MONO (-3996 975);
FORCEPROP 2 LAST CDS_LIB mstr_standard
J 0
(-3775 975);
PAINT ORANGE (-3775 975);
DISPLAY INVISIBLE (-3775 975);
FORCEPROP 1 LAST OFFPAGE TRUE
J 0
(-3450 850);
DISPLAY 0.936170 (-3450 850);
PAINT GREEN (-3450 850);
DISPLAY INVISIBLE (-3450 850);
FORCEPROP 1 LAST COMMENT_BODY TRUE
J 0
(-3650 875);
DISPLAY 0.936170 (-3650 875);
PAINT GREEN (-3650 875);
DISPLAY INVISIBLE (-3650 875);
FORCEPROP 2 LAST PATH I184
J 0
(-3725 1050);
PAINT ORANGE (-3725 1050);
DISPLAY INVISIBLE (-3725 1050);
FORCEADD TAP..6
R 2
(900 4400);
FORCEPROP 3 LASTPIN (850 4400) SIG_NAME M_G_DQS_DN<11>
J 0
(860 4410);
DISPLAY 0.659574 (860 4410);
PAINT MONO (860 4410);
DISPLAY INVISIBLE (860 4410);
FORCEPROP 1 LASTPIN (850 4400) BN 11
J 2
(900 4410);
DISPLAY 0.617021 (900 4410);
PAINT PINK (900 4410);
FORCEPROP 2 LAST CDS_LIB mstr_standard
J 0
(900 4400);
DISPLAY 0.787234 (900 4400);
PAINT MONO (900 4400);
DISPLAY INVISIBLE (900 4400);
FORCEPROP 1 LAST BODY_TYPE PLUMBING
J 2
(900 4350);
DISPLAY 1.234043 (900 4350);
PAINT GREEN (900 4350);
DISPLAY INVISIBLE (900 4350);
FORCEPROP 1 LAST HDL_TAP TRUE
J 2
(575 4275);
DISPLAY 1.234043 (575 4275);
PAINT GREEN (575 4275);
DISPLAY INVISIBLE (575 4275);
FORCEPROP 1 LAST PATH I19
J 2
(900 4400);
DISPLAY 0.936170 (900 4400);
PAINT GREEN (900 4400);
DISPLAY INVISIBLE (900 4400);
FORCEADD P12V_NVDIMM_GHJ..1
(400 2925);
FORCEPROP 3 LASTPIN (400 2875) SIG_NAME P12V_NVDIMM_GHJ\g
J 0
(410 2885);
DISPLAY 0.659574 (410 2885);
PAINT MONO (410 2885);
DISPLAY INVISIBLE (410 2885);
FORCEPROP 1 LAST VOLTAGE 12.0
J 0
(355 2882);
DISPLAY 0.340426 (355 2882);
PAINT SKYBLUE (355 2882);
DISPLAY INVISIBLE (355 2882);
FORCEPROP 2 LAST CDS_LIB mstr_symbols
J 0
(400 2925);
PAINT ORANGE (400 2925);
DISPLAY INVISIBLE (400 2925);
FORCEPROP 1 LAST BODY_TYPE PLUMBING
J 0
(355 2882);
DISPLAY 0.340426 (355 2882);
PAINT GREEN (355 2882);
DISPLAY INVISIBLE (355 2882);
FORCEPROP 1 LAST PATH I197
J 0
(450 2950);
DISPLAY 0.872340 (450 2950);
PAINT AQUA (450 2950);
DISPLAY INVISIBLE (450 2950);
FORCEPROP 1 LAST HDL_POWER P12V_NVDIMM_GHJ
J 1
(400 2975);
DISPLAY 0.872340 (400 2975);
PAINT GREEN (400 2975);
DISPLAY INVISIBLE (400 2975);
FORCEADD OFFPAGE..3
(1600 5050);
FORCEPROP 2 LAST $XR1 78 
J 0
(1904 5050);
DISPLAY 0.638298 (1904 5050);
PAINT MONO (1904 5050);
FORCEPROP 2 LAST $XR0 57 
J 0
(1814 5050);
DISPLAY 0.638298 (1814 5050);
PAINT MONO (1814 5050);
FORCEPROP 2 LAST CDS_LIB mstr_standard
J 0
(1600 5050);
DISPLAY 0.787234 (1600 5050);
PAINT MONO (1600 5050);
DISPLAY INVISIBLE (1600 5050);
FORCEPROP 1 LAST OFFPAGE TRUE
J 0
(1925 4925);
DISPLAY 0.936170 (1925 4925);
PAINT GREEN (1925 4925);
DISPLAY INVISIBLE (1925 4925);
FORCEPROP 1 LAST COMMENT_BODY TRUE
J 0
(1550 4950);
DISPLAY 0.936170 (1550 4950);
PAINT GREEN (1550 4950);
DISPLAY INVISIBLE (1550 4950);
FORCEPROP 2 LAST PATH I2
J 0
(1800 5125);
DISPLAY 0.787234 (1800 5125);
PAINT MONO (1800 5125);
DISPLAY INVISIBLE (1800 5125);
FORCEADD TAP..6
R 2
(900 4200);
FORCEPROP 3 LASTPIN (850 4200) SIG_NAME M_G_DQS_DN<9>
J 0
(860 4210);
DISPLAY 0.659574 (860 4210);
PAINT MONO (860 4210);
DISPLAY INVISIBLE (860 4210);
FORCEPROP 1 LASTPIN (850 4200) BN 9
J 2
(900 4210);
DISPLAY 0.617021 (900 4210);
PAINT PINK (900 4210);
FORCEPROP 2 LAST CDS_LIB mstr_standard
J 0
(900 4200);
DISPLAY 0.787234 (900 4200);
PAINT MONO (900 4200);
DISPLAY INVISIBLE (900 4200);
FORCEPROP 1 LAST BODY_TYPE PLUMBING
J 2
(900 4150);
DISPLAY 1.234043 (900 4150);
PAINT GREEN (900 4150);
DISPLAY INVISIBLE (900 4150);
FORCEPROP 1 LAST HDL_TAP TRUE
J 2
(575 4075);
DISPLAY 1.234043 (575 4075);
PAINT GREEN (575 4075);
DISPLAY INVISIBLE (575 4075);
FORCEPROP 1 LAST PATH I20
J 2
(900 4200);
DISPLAY 0.936170 (900 4200);
PAINT GREEN (900 4200);
DISPLAY INVISIBLE (900 4200);
FORCEADD TAP..6
R 2
(900 4300);
FORCEPROP 3 LASTPIN (850 4300) SIG_NAME M_G_DQS_DN<10>
J 0
(860 4310);
DISPLAY 0.659574 (860 4310);
PAINT MONO (860 4310);
DISPLAY INVISIBLE (860 4310);
FORCEPROP 1 LASTPIN (850 4300) BN 10
J 2
(900 4310);
DISPLAY 0.617021 (900 4310);
PAINT PINK (900 4310);
FORCEPROP 2 LAST CDS_LIB mstr_standard
J 0
(900 4300);
DISPLAY 0.787234 (900 4300);
PAINT MONO (900 4300);
DISPLAY INVISIBLE (900 4300);
FORCEPROP 1 LAST BODY_TYPE PLUMBING
J 2
(900 4250);
DISPLAY 1.234043 (900 4250);
PAINT GREEN (900 4250);
DISPLAY INVISIBLE (900 4250);
FORCEPROP 1 LAST HDL_TAP TRUE
J 2
(575 4175);
DISPLAY 1.234043 (575 4175);
PAINT GREEN (575 4175);
DISPLAY INVISIBLE (575 4175);
FORCEPROP 1 LAST PATH I21
J 2
(900 4300);
DISPLAY 0.936170 (900 4300);
PAINT GREEN (900 4300);
DISPLAY INVISIBLE (900 4300);
FORCEADD TAP..6
R 2
(900 4100);
FORCEPROP 3 LASTPIN (850 4100) SIG_NAME M_G_DQS_DN<8>
J 0
(860 4110);
DISPLAY 0.659574 (860 4110);
PAINT MONO (860 4110);
DISPLAY INVISIBLE (860 4110);
FORCEPROP 1 LASTPIN (850 4100) BN 8
J 2
(900 4110);
DISPLAY 0.617021 (900 4110);
PAINT PINK (900 4110);
FORCEPROP 2 LAST CDS_LIB mstr_standard
J 0
(900 4100);
DISPLAY 0.787234 (900 4100);
PAINT MONO (900 4100);
DISPLAY INVISIBLE (900 4100);
FORCEPROP 1 LAST BODY_TYPE PLUMBING
J 2
(900 4050);
DISPLAY 1.234043 (900 4050);
PAINT GREEN (900 4050);
DISPLAY INVISIBLE (900 4050);
FORCEPROP 1 LAST HDL_TAP TRUE
J 2
(575 3975);
DISPLAY 1.234043 (575 3975);
PAINT GREEN (575 3975);
DISPLAY INVISIBLE (575 3975);
FORCEPROP 1 LAST PATH I22
J 2
(900 4100);
DISPLAY 0.936170 (900 4100);
PAINT GREEN (900 4100);
DISPLAY INVISIBLE (900 4100);
FORCEADD TAP..6
R 2
(900 4000);
FORCEPROP 3 LASTPIN (850 4000) SIG_NAME M_G_DQS_DN<7>
J 0
(860 4010);
DISPLAY 0.659574 (860 4010);
PAINT MONO (860 4010);
DISPLAY INVISIBLE (860 4010);
FORCEPROP 1 LASTPIN (850 4000) BN 7
J 2
(900 4010);
DISPLAY 0.617021 (900 4010);
PAINT PINK (900 4010);
FORCEPROP 2 LAST CDS_LIB mstr_standard
J 0
(900 4000);
DISPLAY 0.787234 (900 4000);
PAINT MONO (900 4000);
DISPLAY INVISIBLE (900 4000);
FORCEPROP 1 LAST BODY_TYPE PLUMBING
J 2
(900 3950);
DISPLAY 1.234043 (900 3950);
PAINT GREEN (900 3950);
DISPLAY INVISIBLE (900 3950);
FORCEPROP 1 LAST HDL_TAP TRUE
J 2
(575 3875);
DISPLAY 1.234043 (575 3875);
PAINT GREEN (575 3875);
DISPLAY INVISIBLE (575 3875);
FORCEPROP 1 LAST PATH I23
J 2
(900 4000);
DISPLAY 0.936170 (900 4000);
PAINT GREEN (900 4000);
DISPLAY INVISIBLE (900 4000);
FORCEADD TAP..6
R 2
(700 4350);
FORCEPROP 3 LASTPIN (650 4350) SIG_NAME M_G_DQS_DP<10>
J 0
(660 4360);
DISPLAY 0.659574 (660 4360);
PAINT MONO (660 4360);
DISPLAY INVISIBLE (660 4360);
FORCEPROP 1 LASTPIN (650 4350) BN 10
J 2
(700 4360);
DISPLAY 0.617021 (700 4360);
PAINT PINK (700 4360);
FORCEPROP 2 LAST CDS_LIB mstr_standard
J 0
(700 4350);
DISPLAY 0.787234 (700 4350);
PAINT MONO (700 4350);
DISPLAY INVISIBLE (700 4350);
FORCEPROP 1 LAST BODY_TYPE PLUMBING
J 2
(700 4300);
DISPLAY 1.234043 (700 4300);
PAINT GREEN (700 4300);
DISPLAY INVISIBLE (700 4300);
FORCEPROP 1 LAST HDL_TAP TRUE
J 2
(375 4225);
DISPLAY 1.234043 (375 4225);
PAINT GREEN (375 4225);
DISPLAY INVISIBLE (375 4225);
FORCEPROP 1 LAST PATH I24
J 2
(700 4350);
DISPLAY 0.936170 (700 4350);
PAINT GREEN (700 4350);
DISPLAY INVISIBLE (700 4350);
FORCEADD TAP..6
R 2
(700 4250);
FORCEPROP 3 LASTPIN (650 4250) SIG_NAME M_G_DQS_DP<9>
J 0
(660 4260);
DISPLAY 0.659574 (660 4260);
PAINT MONO (660 4260);
DISPLAY INVISIBLE (660 4260);
FORCEPROP 1 LASTPIN (650 4250) BN 9
J 2
(700 4260);
DISPLAY 0.617021 (700 4260);
PAINT PINK (700 4260);
FORCEPROP 2 LAST CDS_LIB mstr_standard
J 0
(700 4250);
DISPLAY 0.787234 (700 4250);
PAINT MONO (700 4250);
DISPLAY INVISIBLE (700 4250);
FORCEPROP 1 LAST BODY_TYPE PLUMBING
J 2
(700 4200);
DISPLAY 1.234043 (700 4200);
PAINT GREEN (700 4200);
DISPLAY INVISIBLE (700 4200);
FORCEPROP 1 LAST HDL_TAP TRUE
J 2
(375 4125);
DISPLAY 1.234043 (375 4125);
PAINT GREEN (375 4125);
DISPLAY INVISIBLE (375 4125);
FORCEPROP 1 LAST PATH I25
J 2
(700 4250);
DISPLAY 0.936170 (700 4250);
PAINT GREEN (700 4250);
DISPLAY INVISIBLE (700 4250);
FORCEADD TAP..6
R 2
(700 3950);
FORCEPROP 3 LASTPIN (650 3950) SIG_NAME M_G_DQS_DP<6>
J 0
(660 3960);
DISPLAY 0.659574 (660 3960);
PAINT MONO (660 3960);
DISPLAY INVISIBLE (660 3960);
FORCEPROP 1 LASTPIN (650 3950) BN 6
J 2
(700 3960);
DISPLAY 0.617021 (700 3960);
PAINT PINK (700 3960);
FORCEPROP 2 LAST CDS_LIB mstr_standard
J 0
(700 3950);
DISPLAY 0.787234 (700 3950);
PAINT MONO (700 3950);
DISPLAY INVISIBLE (700 3950);
FORCEPROP 1 LAST BODY_TYPE PLUMBING
J 2
(700 3900);
DISPLAY 1.234043 (700 3900);
PAINT GREEN (700 3900);
DISPLAY INVISIBLE (700 3900);
FORCEPROP 1 LAST HDL_TAP TRUE
J 2
(375 3825);
DISPLAY 1.234043 (375 3825);
PAINT GREEN (375 3825);
DISPLAY INVISIBLE (375 3825);
FORCEPROP 1 LAST PATH I26
J 2
(700 3950);
DISPLAY 0.936170 (700 3950);
PAINT GREEN (700 3950);
DISPLAY INVISIBLE (700 3950);
FORCEADD TAP..6
R 2
(700 4050);
FORCEPROP 3 LASTPIN (650 4050) SIG_NAME M_G_DQS_DP<7>
J 0
(660 4060);
DISPLAY 0.659574 (660 4060);
PAINT MONO (660 4060);
DISPLAY INVISIBLE (660 4060);
FORCEPROP 1 LASTPIN (650 4050) BN 7
J 2
(700 4060);
DISPLAY 0.617021 (700 4060);
PAINT PINK (700 4060);
FORCEPROP 2 LAST CDS_LIB mstr_standard
J 0
(700 4050);
DISPLAY 0.787234 (700 4050);
PAINT MONO (700 4050);
DISPLAY INVISIBLE (700 4050);
FORCEPROP 1 LAST BODY_TYPE PLUMBING
J 2
(700 4000);
DISPLAY 1.234043 (700 4000);
PAINT GREEN (700 4000);
DISPLAY INVISIBLE (700 4000);
FORCEPROP 1 LAST HDL_TAP TRUE
J 2
(375 3925);
DISPLAY 1.234043 (375 3925);
PAINT GREEN (375 3925);
DISPLAY INVISIBLE (375 3925);
FORCEPROP 1 LAST PATH I27
J 2
(700 4050);
DISPLAY 0.936170 (700 4050);
PAINT GREEN (700 4050);
DISPLAY INVISIBLE (700 4050);
FORCEADD TAP..6
R 2
(700 4150);
FORCEPROP 3 LASTPIN (650 4150) SIG_NAME M_G_DQS_DP<8>
J 0
(660 4160);
DISPLAY 0.659574 (660 4160);
PAINT MONO (660 4160);
DISPLAY INVISIBLE (660 4160);
FORCEPROP 1 LASTPIN (650 4150) BN 8
J 2
(700 4160);
DISPLAY 0.617021 (700 4160);
PAINT PINK (700 4160);
FORCEPROP 2 LAST CDS_LIB mstr_standard
J 0
(700 4150);
DISPLAY 0.787234 (700 4150);
PAINT MONO (700 4150);
DISPLAY INVISIBLE (700 4150);
FORCEPROP 1 LAST BODY_TYPE PLUMBING
J 2
(700 4100);
DISPLAY 1.234043 (700 4100);
PAINT GREEN (700 4100);
DISPLAY INVISIBLE (700 4100);
FORCEPROP 1 LAST HDL_TAP TRUE
J 2
(375 4025);
DISPLAY 1.234043 (375 4025);
PAINT GREEN (375 4025);
DISPLAY INVISIBLE (375 4025);
FORCEPROP 1 LAST PATH I28
J 2
(700 4150);
DISPLAY 0.936170 (700 4150);
PAINT GREEN (700 4150);
DISPLAY INVISIBLE (700 4150);
FORCEADD TAP..6
R 2
(900 3900);
FORCEPROP 3 LASTPIN (850 3900) SIG_NAME M_G_DQS_DN<6>
J 0
(860 3910);
DISPLAY 0.659574 (860 3910);
PAINT MONO (860 3910);
DISPLAY INVISIBLE (860 3910);
FORCEPROP 1 LASTPIN (850 3900) BN 6
J 2
(900 3910);
DISPLAY 0.617021 (900 3910);
PAINT PINK (900 3910);
FORCEPROP 2 LAST CDS_LIB mstr_standard
J 0
(900 3900);
DISPLAY 0.787234 (900 3900);
PAINT MONO (900 3900);
DISPLAY INVISIBLE (900 3900);
FORCEPROP 1 LAST BODY_TYPE PLUMBING
J 2
(900 3850);
DISPLAY 1.234043 (900 3850);
PAINT GREEN (900 3850);
DISPLAY INVISIBLE (900 3850);
FORCEPROP 1 LAST HDL_TAP TRUE
J 2
(575 3775);
DISPLAY 1.234043 (575 3775);
PAINT GREEN (575 3775);
DISPLAY INVISIBLE (575 3775);
FORCEPROP 1 LAST PATH I29
J 2
(900 3900);
DISPLAY 0.936170 (900 3900);
PAINT GREEN (900 3900);
DISPLAY INVISIBLE (900 3900);
FORCEADD TAP..6
R 2
(900 5000);
FORCEPROP 3 LASTPIN (850 5000) SIG_NAME M_G_DQS_DN<17>
J 0
(860 5010);
DISPLAY 0.659574 (860 5010);
PAINT MONO (860 5010);
DISPLAY INVISIBLE (860 5010);
FORCEPROP 1 LASTPIN (850 5000) BN 17
J 2
(900 5010);
DISPLAY 0.617021 (900 5010);
PAINT PINK (900 5010);
FORCEPROP 2 LAST CDS_LIB mstr_standard
J 2
(900 5000);
DISPLAY 0.787234 (900 5000);
PAINT MONO (900 5000);
DISPLAY INVISIBLE (900 5000);
FORCEPROP 1 LAST BODY_TYPE PLUMBING
J 2
(900 4950);
DISPLAY 1.234043 (900 4950);
PAINT GREEN (900 4950);
DISPLAY INVISIBLE (900 4950);
FORCEPROP 1 LAST HDL_TAP TRUE
J 2
(575 4875);
DISPLAY 1.234043 (575 4875);
PAINT GREEN (575 4875);
DISPLAY INVISIBLE (575 4875);
FORCEPROP 1 LAST PATH I3
J 2
(900 5000);
DISPLAY 0.936170 (900 5000);
PAINT GREEN (900 5000);
DISPLAY INVISIBLE (900 5000);
FORCEADD TAP..6
R 2
(900 3700);
FORCEPROP 3 LASTPIN (850 3700) SIG_NAME M_G_DQS_DN<4>
J 0
(860 3710);
DISPLAY 0.659574 (860 3710);
PAINT MONO (860 3710);
DISPLAY INVISIBLE (860 3710);
FORCEPROP 1 LASTPIN (850 3700) BN 4
J 2
(900 3710);
DISPLAY 0.617021 (900 3710);
PAINT PINK (900 3710);
FORCEPROP 2 LAST CDS_LIB mstr_standard
J 0
(900 3700);
DISPLAY 0.787234 (900 3700);
PAINT MONO (900 3700);
DISPLAY INVISIBLE (900 3700);
FORCEPROP 1 LAST BODY_TYPE PLUMBING
J 2
(900 3650);
DISPLAY 1.234043 (900 3650);
PAINT GREEN (900 3650);
DISPLAY INVISIBLE (900 3650);
FORCEPROP 1 LAST HDL_TAP TRUE
J 2
(575 3575);
DISPLAY 1.234043 (575 3575);
PAINT GREEN (575 3575);
DISPLAY INVISIBLE (575 3575);
FORCEPROP 1 LAST PATH I30
J 2
(900 3700);
DISPLAY 0.936170 (900 3700);
PAINT GREEN (900 3700);
DISPLAY INVISIBLE (900 3700);
FORCEADD TAP..6
R 2
(900 3800);
FORCEPROP 3 LASTPIN (850 3800) SIG_NAME M_G_DQS_DN<5>
J 0
(860 3810);
DISPLAY 0.659574 (860 3810);
PAINT MONO (860 3810);
DISPLAY INVISIBLE (860 3810);
FORCEPROP 1 LASTPIN (850 3800) BN 5
J 2
(900 3810);
DISPLAY 0.617021 (900 3810);
PAINT PINK (900 3810);
FORCEPROP 2 LAST CDS_LIB mstr_standard
J 0
(900 3800);
DISPLAY 0.787234 (900 3800);
PAINT MONO (900 3800);
DISPLAY INVISIBLE (900 3800);
FORCEPROP 1 LAST BODY_TYPE PLUMBING
J 2
(900 3750);
DISPLAY 1.234043 (900 3750);
PAINT GREEN (900 3750);
DISPLAY INVISIBLE (900 3750);
FORCEPROP 1 LAST HDL_TAP TRUE
J 2
(575 3675);
DISPLAY 1.234043 (575 3675);
PAINT GREEN (575 3675);
DISPLAY INVISIBLE (575 3675);
FORCEPROP 1 LAST PATH I31
J 2
(900 3800);
DISPLAY 0.936170 (900 3800);
PAINT GREEN (900 3800);
DISPLAY INVISIBLE (900 3800);
FORCEADD TAP..6
R 2
(900 3500);
FORCEPROP 3 LASTPIN (850 3500) SIG_NAME M_G_DQS_DN<2>
J 0
(860 3510);
DISPLAY 0.659574 (860 3510);
PAINT MONO (860 3510);
DISPLAY INVISIBLE (860 3510);
FORCEPROP 1 LASTPIN (850 3500) BN 2
J 2
(900 3510);
DISPLAY 0.617021 (900 3510);
PAINT PINK (900 3510);
FORCEPROP 2 LAST CDS_LIB mstr_standard
J 0
(900 3500);
DISPLAY 0.787234 (900 3500);
PAINT MONO (900 3500);
DISPLAY INVISIBLE (900 3500);
FORCEPROP 1 LAST BODY_TYPE PLUMBING
J 2
(900 3450);
DISPLAY 1.234043 (900 3450);
PAINT GREEN (900 3450);
DISPLAY INVISIBLE (900 3450);
FORCEPROP 1 LAST HDL_TAP TRUE
J 2
(575 3375);
DISPLAY 1.234043 (575 3375);
PAINT GREEN (575 3375);
DISPLAY INVISIBLE (575 3375);
FORCEPROP 1 LAST PATH I32
J 2
(900 3500);
DISPLAY 0.936170 (900 3500);
PAINT GREEN (900 3500);
DISPLAY INVISIBLE (900 3500);
FORCEADD TAP..6
R 2
(900 3600);
FORCEPROP 3 LASTPIN (850 3600) SIG_NAME M_G_DQS_DN<3>
J 0
(860 3610);
DISPLAY 0.659574 (860 3610);
PAINT MONO (860 3610);
DISPLAY INVISIBLE (860 3610);
FORCEPROP 1 LASTPIN (850 3600) BN 3
J 2
(900 3610);
DISPLAY 0.617021 (900 3610);
PAINT PINK (900 3610);
FORCEPROP 2 LAST CDS_LIB mstr_standard
J 0
(900 3600);
DISPLAY 0.787234 (900 3600);
PAINT MONO (900 3600);
DISPLAY INVISIBLE (900 3600);
FORCEPROP 1 LAST BODY_TYPE PLUMBING
J 2
(900 3550);
DISPLAY 1.234043 (900 3550);
PAINT GREEN (900 3550);
DISPLAY INVISIBLE (900 3550);
FORCEPROP 1 LAST HDL_TAP TRUE
J 2
(575 3475);
DISPLAY 1.234043 (575 3475);
PAINT GREEN (575 3475);
DISPLAY INVISIBLE (575 3475);
FORCEPROP 1 LAST PATH I33
J 2
(900 3600);
DISPLAY 0.936170 (900 3600);
PAINT GREEN (900 3600);
DISPLAY INVISIBLE (900 3600);
FORCEADD TAP..6
R 2
(700 3750);
FORCEPROP 3 LASTPIN (650 3750) SIG_NAME M_G_DQS_DP<4>
J 0
(660 3760);
DISPLAY 0.659574 (660 3760);
PAINT MONO (660 3760);
DISPLAY INVISIBLE (660 3760);
FORCEPROP 1 LASTPIN (650 3750) BN 4
J 2
(700 3760);
DISPLAY 0.617021 (700 3760);
PAINT PINK (700 3760);
FORCEPROP 2 LAST CDS_LIB mstr_standard
J 0
(700 3750);
DISPLAY 0.787234 (700 3750);
PAINT MONO (700 3750);
DISPLAY INVISIBLE (700 3750);
FORCEPROP 1 LAST BODY_TYPE PLUMBING
J 2
(700 3700);
DISPLAY 1.234043 (700 3700);
PAINT GREEN (700 3700);
DISPLAY INVISIBLE (700 3700);
FORCEPROP 1 LAST HDL_TAP TRUE
J 2
(375 3625);
DISPLAY 1.234043 (375 3625);
PAINT GREEN (375 3625);
DISPLAY INVISIBLE (375 3625);
FORCEPROP 1 LAST PATH I34
J 2
(700 3750);
DISPLAY 0.936170 (700 3750);
PAINT GREEN (700 3750);
DISPLAY INVISIBLE (700 3750);
FORCEADD TAP..6
R 2
(700 3850);
FORCEPROP 3 LASTPIN (650 3850) SIG_NAME M_G_DQS_DP<5>
J 0
(660 3860);
DISPLAY 0.659574 (660 3860);
PAINT MONO (660 3860);
DISPLAY INVISIBLE (660 3860);
FORCEPROP 1 LASTPIN (650 3850) BN 5
J 2
(700 3860);
DISPLAY 0.617021 (700 3860);
PAINT PINK (700 3860);
FORCEPROP 2 LAST CDS_LIB mstr_standard
J 0
(700 3850);
DISPLAY 0.787234 (700 3850);
PAINT MONO (700 3850);
DISPLAY INVISIBLE (700 3850);
FORCEPROP 1 LAST BODY_TYPE PLUMBING
J 2
(700 3800);
DISPLAY 1.234043 (700 3800);
PAINT GREEN (700 3800);
DISPLAY INVISIBLE (700 3800);
FORCEPROP 1 LAST HDL_TAP TRUE
J 2
(375 3725);
DISPLAY 1.234043 (375 3725);
PAINT GREEN (375 3725);
DISPLAY INVISIBLE (375 3725);
FORCEPROP 1 LAST PATH I35
J 2
(700 3850);
DISPLAY 0.936170 (700 3850);
PAINT GREEN (700 3850);
DISPLAY INVISIBLE (700 3850);
FORCEADD TAP..6
R 2
(700 3550);
FORCEPROP 3 LASTPIN (650 3550) SIG_NAME M_G_DQS_DP<2>
J 0
(660 3560);
DISPLAY 0.659574 (660 3560);
PAINT MONO (660 3560);
DISPLAY INVISIBLE (660 3560);
FORCEPROP 1 LASTPIN (650 3550) BN 2
J 2
(700 3560);
DISPLAY 0.617021 (700 3560);
PAINT PINK (700 3560);
FORCEPROP 2 LAST CDS_LIB mstr_standard
J 0
(700 3550);
DISPLAY 0.787234 (700 3550);
PAINT MONO (700 3550);
DISPLAY INVISIBLE (700 3550);
FORCEPROP 1 LAST BODY_TYPE PLUMBING
J 2
(700 3500);
DISPLAY 1.234043 (700 3500);
PAINT GREEN (700 3500);
DISPLAY INVISIBLE (700 3500);
FORCEPROP 1 LAST HDL_TAP TRUE
J 2
(375 3425);
DISPLAY 1.234043 (375 3425);
PAINT GREEN (375 3425);
DISPLAY INVISIBLE (375 3425);
FORCEPROP 1 LAST PATH I36
J 2
(700 3550);
DISPLAY 0.936170 (700 3550);
PAINT GREEN (700 3550);
DISPLAY INVISIBLE (700 3550);
FORCEADD TAP..6
R 2
(700 3450);
FORCEPROP 3 LASTPIN (650 3450) SIG_NAME M_G_DQS_DP<1>
J 0
(660 3460);
DISPLAY 0.659574 (660 3460);
PAINT MONO (660 3460);
DISPLAY INVISIBLE (660 3460);
FORCEPROP 1 LASTPIN (650 3450) BN 1
J 2
(700 3460);
DISPLAY 0.617021 (700 3460);
PAINT PINK (700 3460);
FORCEPROP 2 LAST CDS_LIB mstr_standard
J 0
(700 3450);
DISPLAY 0.787234 (700 3450);
PAINT MONO (700 3450);
DISPLAY INVISIBLE (700 3450);
FORCEPROP 1 LAST BODY_TYPE PLUMBING
J 2
(700 3400);
DISPLAY 1.234043 (700 3400);
PAINT GREEN (700 3400);
DISPLAY INVISIBLE (700 3400);
FORCEPROP 1 LAST HDL_TAP TRUE
J 2
(375 3325);
DISPLAY 1.234043 (375 3325);
PAINT GREEN (375 3325);
DISPLAY INVISIBLE (375 3325);
FORCEPROP 1 LAST PATH I37
J 2
(700 3450);
DISPLAY 0.936170 (700 3450);
PAINT GREEN (700 3450);
DISPLAY INVISIBLE (700 3450);
FORCEADD TAP..6
R 2
(700 3650);
FORCEPROP 3 LASTPIN (650 3650) SIG_NAME M_G_DQS_DP<3>
J 0
(660 3660);
DISPLAY 0.659574 (660 3660);
PAINT MONO (660 3660);
DISPLAY INVISIBLE (660 3660);
FORCEPROP 1 LASTPIN (650 3650) BN 3
J 2
(700 3660);
DISPLAY 0.617021 (700 3660);
PAINT PINK (700 3660);
FORCEPROP 2 LAST CDS_LIB mstr_standard
J 0
(700 3650);
DISPLAY 0.787234 (700 3650);
PAINT MONO (700 3650);
DISPLAY INVISIBLE (700 3650);
FORCEPROP 1 LAST BODY_TYPE PLUMBING
J 2
(700 3600);
DISPLAY 1.234043 (700 3600);
PAINT GREEN (700 3600);
DISPLAY INVISIBLE (700 3600);
FORCEPROP 1 LAST HDL_TAP TRUE
J 2
(375 3525);
DISPLAY 1.234043 (375 3525);
PAINT GREEN (375 3525);
DISPLAY INVISIBLE (375 3525);
FORCEPROP 1 LAST PATH I38
J 2
(700 3650);
DISPLAY 0.936170 (700 3650);
PAINT GREEN (700 3650);
DISPLAY INVISIBLE (700 3650);
FORCEADD TAP..6
R 2
(900 3300);
FORCEPROP 3 LASTPIN (850 3300) SIG_NAME M_G_DQS_DN<0>
J 0
(860 3310);
DISPLAY 0.659574 (860 3310);
PAINT MONO (860 3310);
DISPLAY INVISIBLE (860 3310);
FORCEPROP 1 LASTPIN (850 3300) BN 0
J 2
(900 3310);
DISPLAY 0.617021 (900 3310);
PAINT PINK (900 3310);
FORCEPROP 2 LAST CDS_LIB mstr_standard
J 0
(900 3300);
DISPLAY 0.787234 (900 3300);
PAINT MONO (900 3300);
DISPLAY INVISIBLE (900 3300);
FORCEPROP 1 LAST BODY_TYPE PLUMBING
J 2
(900 3250);
DISPLAY 1.234043 (900 3250);
PAINT GREEN (900 3250);
DISPLAY INVISIBLE (900 3250);
FORCEPROP 1 LAST HDL_TAP TRUE
J 2
(575 3175);
DISPLAY 1.234043 (575 3175);
PAINT GREEN (575 3175);
DISPLAY INVISIBLE (575 3175);
FORCEPROP 1 LAST PATH I39
J 2
(900 3300);
DISPLAY 0.936170 (900 3300);
PAINT GREEN (900 3300);
DISPLAY INVISIBLE (900 3300);
FORCEADD TAP..6
R 2
(700 5050);
FORCEPROP 3 LASTPIN (650 5050) SIG_NAME M_G_DQS_DP<17>
J 0
(660 5060);
DISPLAY 0.659574 (660 5060);
PAINT MONO (660 5060);
DISPLAY INVISIBLE (660 5060);
FORCEPROP 1 LASTPIN (650 5050) BN 17
J 2
(700 5060);
DISPLAY 0.617021 (700 5060);
PAINT PINK (700 5060);
FORCEPROP 2 LAST CDS_LIB mstr_standard
J 2
(700 5050);
DISPLAY 0.787234 (700 5050);
PAINT MONO (700 5050);
DISPLAY INVISIBLE (700 5050);
FORCEPROP 1 LAST BODY_TYPE PLUMBING
J 2
(700 5000);
DISPLAY 1.234043 (700 5000);
PAINT GREEN (700 5000);
DISPLAY INVISIBLE (700 5000);
FORCEPROP 1 LAST HDL_TAP TRUE
J 2
(375 4925);
DISPLAY 1.234043 (375 4925);
PAINT GREEN (375 4925);
DISPLAY INVISIBLE (375 4925);
FORCEPROP 1 LAST PATH I4
J 2
(700 5050);
DISPLAY 0.936170 (700 5050);
PAINT GREEN (700 5050);
DISPLAY INVISIBLE (700 5050);
FORCEADD TAP..6
R 2
(900 3400);
FORCEPROP 3 LASTPIN (850 3400) SIG_NAME M_G_DQS_DN<1>
J 0
(860 3410);
DISPLAY 0.659574 (860 3410);
PAINT MONO (860 3410);
DISPLAY INVISIBLE (860 3410);
FORCEPROP 1 LASTPIN (850 3400) BN 1
J 2
(900 3410);
DISPLAY 0.617021 (900 3410);
PAINT PINK (900 3410);
FORCEPROP 2 LAST CDS_LIB mstr_standard
J 0
(900 3400);
DISPLAY 0.787234 (900 3400);
PAINT MONO (900 3400);
DISPLAY INVISIBLE (900 3400);
FORCEPROP 1 LAST BODY_TYPE PLUMBING
J 2
(900 3350);
DISPLAY 1.234043 (900 3350);
PAINT GREEN (900 3350);
DISPLAY INVISIBLE (900 3350);
FORCEPROP 1 LAST HDL_TAP TRUE
J 2
(575 3275);
DISPLAY 1.234043 (575 3275);
PAINT GREEN (575 3275);
DISPLAY INVISIBLE (575 3275);
FORCEPROP 1 LAST PATH I40
J 2
(900 3400);
DISPLAY 0.936170 (900 3400);
PAINT GREEN (900 3400);
DISPLAY INVISIBLE (900 3400);
FORCEADD TAP..6
R 2
(700 3350);
FORCEPROP 3 LASTPIN (650 3350) SIG_NAME M_G_DQS_DP<0>
J 0
(660 3360);
DISPLAY 0.659574 (660 3360);
PAINT MONO (660 3360);
DISPLAY INVISIBLE (660 3360);
FORCEPROP 1 LASTPIN (650 3350) BN 0
J 2
(700 3360);
DISPLAY 0.617021 (700 3360);
PAINT PINK (700 3360);
FORCEPROP 2 LAST CDS_LIB mstr_standard
J 0
(700 3350);
DISPLAY 0.787234 (700 3350);
PAINT MONO (700 3350);
DISPLAY INVISIBLE (700 3350);
FORCEPROP 1 LAST BODY_TYPE PLUMBING
J 2
(700 3300);
DISPLAY 1.234043 (700 3300);
PAINT GREEN (700 3300);
DISPLAY INVISIBLE (700 3300);
FORCEPROP 1 LAST HDL_TAP TRUE
J 2
(375 3225);
DISPLAY 1.234043 (375 3225);
PAINT GREEN (375 3225);
DISPLAY INVISIBLE (375 3225);
FORCEPROP 1 LAST PATH I41
J 2
(700 3350);
DISPLAY 0.936170 (700 3350);
PAINT GREEN (700 3350);
DISPLAY INVISIBLE (700 3350);
FORCEADD SCONN288_H44441004..3
(1800 2200);
FORCEPROP 2 LASTPIN (1300 2300) $PN 48
J 2
(1290 2310);
DISPLAY 0.617021 (1290 2310);
PAINT ORANGE (1290 2310);
FORCEPROP 2 LASTPIN (1300 1450) $PN 120
J 2
(1290 1460);
DISPLAY 0.617021 (1290 1460);
PAINT ORANGE (1290 1460);
FORCEPROP 2 LASTPIN (1300 1500) $PN 118
J 2
(1290 1510);
DISPLAY 0.617021 (1290 1510);
PAINT ORANGE (1290 1510);
FORCEPROP 2 LASTPIN (2300 1950) $PN 243
J 0
(2310 1960);
DISPLAY 0.617021 (2310 1960);
PAINT ORANGE (2310 1960);
FORCEPROP 1 LAST LOCATION J1G1
J 0
(1350 3600);
DISPLAY 0.617021 (1350 3600);
PAINT AQUA (1350 3600);
FORCEPROP 1 LAST PART_NUMBER H44441-004
J 0
(1350 850);
DISPLAY 0.617021 (1350 850);
PAINT BLUE (1350 850);
FORCEPROP 1 LAST MATERIAL SCONN
J 0
(1350 3550);
DISPLAY 0.617021 (1350 3550);
PAINT SKYBLUE (1350 3550);
FORCEPROP 2 LASTPIN (1300 3350) $PN 2
J 2
(1290 3360);
DISPLAY 0.617021 (1290 3360);
PAINT ORANGE (1290 3360);
FORCEPROP 2 LASTPIN (1300 3300) $PN 4
J 2
(1290 3310);
DISPLAY 0.617021 (1290 3310);
PAINT ORANGE (1290 3310);
FORCEPROP 2 LASTPIN (1300 3250) $PN 6
J 2
(1290 3260);
DISPLAY 0.617021 (1290 3260);
PAINT ORANGE (1290 3260);
FORCEPROP 2 LASTPIN (1300 3200) $PN 9
J 2
(1290 3210);
DISPLAY 0.617021 (1290 3210);
PAINT ORANGE (1290 3210);
FORCEPROP 2 LASTPIN (1300 3150) $PN 11
J 2
(1290 3160);
DISPLAY 0.617021 (1290 3160);
PAINT ORANGE (1290 3160);
FORCEPROP 2 LASTPIN (1300 3100) $PN 13
J 2
(1290 3110);
DISPLAY 0.617021 (1290 3110);
PAINT ORANGE (1290 3110);
FORCEPROP 2 LASTPIN (1300 3050) $PN 15
J 2
(1290 3060);
DISPLAY 0.617021 (1290 3060);
PAINT ORANGE (1290 3060);
FORCEPROP 2 LASTPIN (1300 3000) $PN 17
J 2
(1290 3010);
DISPLAY 0.617021 (1290 3010);
PAINT ORANGE (1290 3010);
FORCEPROP 2 LASTPIN (1300 2950) $PN 20
J 2
(1290 2960);
DISPLAY 0.617021 (1290 2960);
PAINT ORANGE (1290 2960);
FORCEPROP 2 LASTPIN (1300 2900) $PN 22
J 2
(1290 2910);
DISPLAY 0.617021 (1290 2910);
PAINT ORANGE (1290 2910);
FORCEPROP 2 LASTPIN (1300 2850) $PN 24
J 2
(1290 2860);
DISPLAY 0.617021 (1290 2860);
PAINT ORANGE (1290 2860);
FORCEPROP 2 LASTPIN (1300 2800) $PN 26
J 2
(1290 2810);
DISPLAY 0.617021 (1290 2810);
PAINT ORANGE (1290 2810);
FORCEPROP 2 LASTPIN (1300 2750) $PN 28
J 2
(1290 2760);
DISPLAY 0.617021 (1290 2760);
PAINT ORANGE (1290 2760);
FORCEPROP 2 LASTPIN (1300 2700) $PN 31
J 2
(1290 2710);
DISPLAY 0.617021 (1290 2710);
PAINT ORANGE (1290 2710);
FORCEPROP 2 LASTPIN (1300 2650) $PN 33
J 2
(1290 2660);
DISPLAY 0.617021 (1290 2660);
PAINT ORANGE (1290 2660);
FORCEPROP 2 LASTPIN (1300 2600) $PN 35
J 2
(1290 2610);
DISPLAY 0.617021 (1290 2610);
PAINT ORANGE (1290 2610);
FORCEPROP 2 LASTPIN (1300 2550) $PN 37
J 2
(1290 2560);
DISPLAY 0.617021 (1290 2560);
PAINT ORANGE (1290 2560);
FORCEPROP 2 LASTPIN (1300 2500) $PN 39
J 2
(1290 2510);
DISPLAY 0.617021 (1290 2510);
PAINT ORANGE (1290 2510);
FORCEPROP 2 LASTPIN (1300 2450) $PN 42
J 2
(1290 2460);
DISPLAY 0.617021 (1290 2460);
PAINT ORANGE (1290 2460);
FORCEPROP 2 LASTPIN (1300 2400) $PN 44
J 2
(1290 2410);
DISPLAY 0.617021 (1290 2410);
PAINT ORANGE (1290 2410);
FORCEPROP 2 LASTPIN (1300 2350) $PN 46
J 2
(1290 2360);
DISPLAY 0.617021 (1290 2360);
PAINT ORANGE (1290 2360);
FORCEPROP 2 LASTPIN (1300 2250) $PN 50
J 2
(1290 2260);
DISPLAY 0.617021 (1290 2260);
PAINT ORANGE (1290 2260);
FORCEPROP 2 LASTPIN (1300 2200) $PN 53
J 2
(1290 2210);
DISPLAY 0.617021 (1290 2210);
PAINT ORANGE (1290 2210);
FORCEPROP 2 LASTPIN (1300 2150) $PN 55
J 2
(1290 2160);
DISPLAY 0.617021 (1290 2160);
PAINT ORANGE (1290 2160);
FORCEPROP 2 LASTPIN (1300 2100) $PN 57
J 2
(1290 2110);
DISPLAY 0.617021 (1290 2110);
PAINT ORANGE (1290 2110);
FORCEPROP 2 LASTPIN (1300 2050) $PN 94
J 2
(1290 2060);
DISPLAY 0.617021 (1290 2060);
PAINT ORANGE (1290 2060);
FORCEPROP 2 LASTPIN (1300 2000) $PN 96
J 2
(1290 2010);
DISPLAY 0.617021 (1290 2010);
PAINT ORANGE (1290 2010);
FORCEPROP 2 LASTPIN (1300 1950) $PN 98
J 2
(1290 1960);
DISPLAY 0.617021 (1290 1960);
PAINT ORANGE (1290 1960);
FORCEPROP 2 LASTPIN (1300 1900) $PN 101
J 2
(1290 1910);
DISPLAY 0.617021 (1290 1910);
PAINT ORANGE (1290 1910);
FORCEPROP 2 LASTPIN (1300 1800) $PN 105
J 2
(1290 1810);
DISPLAY 0.617021 (1290 1810);
PAINT ORANGE (1290 1810);
FORCEPROP 2 LASTPIN (1300 1750) $PN 107
J 2
(1290 1760);
DISPLAY 0.617021 (1290 1760);
PAINT ORANGE (1290 1760);
FORCEPROP 2 LASTPIN (1300 1700) $PN 109
J 2
(1290 1710);
DISPLAY 0.617021 (1290 1710);
PAINT ORANGE (1290 1710);
FORCEPROP 2 LASTPIN (1300 1650) $PN 112
J 2
(1290 1660);
DISPLAY 0.617021 (1290 1660);
PAINT ORANGE (1290 1660);
FORCEPROP 2 LASTPIN (1300 1600) $PN 114
J 2
(1290 1610);
DISPLAY 0.617021 (1290 1610);
PAINT ORANGE (1290 1610);
FORCEPROP 2 LASTPIN (1300 1550) $PN 116
J 2
(1290 1560);
DISPLAY 0.617021 (1290 1560);
PAINT ORANGE (1290 1560);
FORCEPROP 2 LASTPIN (1300 1400) $PN 123
J 2
(1290 1410);
DISPLAY 0.617021 (1290 1410);
PAINT ORANGE (1290 1410);
FORCEPROP 2 LASTPIN (1300 1350) $PN 125
J 2
(1290 1360);
DISPLAY 0.617021 (1290 1360);
PAINT ORANGE (1290 1360);
FORCEPROP 2 LASTPIN (1300 1300) $PN 127
J 2
(1290 1310);
DISPLAY 0.617021 (1290 1310);
PAINT ORANGE (1290 1310);
FORCEPROP 2 LASTPIN (1300 1250) $PN 129
J 2
(1290 1260);
DISPLAY 0.617021 (1290 1260);
PAINT ORANGE (1290 1260);
FORCEPROP 2 LASTPIN (1300 1200) $PN 131
J 2
(1290 1210);
DISPLAY 0.617021 (1290 1210);
PAINT ORANGE (1290 1210);
FORCEPROP 2 LASTPIN (1300 1150) $PN 134
J 2
(1290 1160);
DISPLAY 0.617021 (1290 1160);
PAINT ORANGE (1290 1160);
FORCEPROP 2 LASTPIN (1300 1100) $PN 136
J 2
(1290 1110);
DISPLAY 0.617021 (1290 1110);
PAINT ORANGE (1290 1110);
FORCEPROP 2 LASTPIN (1300 1050) $PN 138
J 2
(1290 1060);
DISPLAY 0.617021 (1290 1060);
PAINT ORANGE (1290 1060);
FORCEPROP 2 LASTPIN (2300 3350) $PN 147
J 0
(2310 3360);
DISPLAY 0.617021 (2310 3360);
PAINT ORANGE (2310 3360);
FORCEPROP 2 LASTPIN (2300 3300) $PN 149
J 0
(2310 3310);
DISPLAY 0.617021 (2310 3310);
PAINT ORANGE (2310 3310);
FORCEPROP 2 LASTPIN (2300 3250) $PN 151
J 0
(2310 3260);
DISPLAY 0.617021 (2310 3260);
PAINT ORANGE (2310 3260);
FORCEPROP 2 LASTPIN (2300 3200) $PN 154
J 0
(2310 3210);
DISPLAY 0.617021 (2310 3210);
PAINT ORANGE (2310 3210);
FORCEPROP 2 LASTPIN (2300 3150) $PN 156
J 0
(2310 3160);
DISPLAY 0.617021 (2310 3160);
PAINT ORANGE (2310 3160);
FORCEPROP 2 LASTPIN (2300 3100) $PN 158
J 0
(2310 3110);
DISPLAY 0.617021 (2310 3110);
PAINT ORANGE (2310 3110);
FORCEPROP 2 LASTPIN (2300 3050) $PN 160
J 0
(2310 3060);
DISPLAY 0.617021 (2310 3060);
PAINT ORANGE (2310 3060);
FORCEPROP 2 LASTPIN (2300 3000) $PN 162
J 0
(2310 3010);
DISPLAY 0.617021 (2310 3010);
PAINT ORANGE (2310 3010);
FORCEPROP 2 LASTPIN (2300 2950) $PN 165
J 0
(2310 2960);
DISPLAY 0.617021 (2310 2960);
PAINT ORANGE (2310 2960);
FORCEPROP 2 LASTPIN (2300 2900) $PN 167
J 0
(2310 2910);
DISPLAY 0.617021 (2310 2910);
PAINT ORANGE (2310 2910);
FORCEPROP 2 LASTPIN (2300 2850) $PN 169
J 0
(2310 2860);
DISPLAY 0.617021 (2310 2860);
PAINT ORANGE (2310 2860);
FORCEPROP 2 LASTPIN (2300 2800) $PN 171
J 0
(2310 2810);
DISPLAY 0.617021 (2310 2810);
PAINT ORANGE (2310 2810);
FORCEPROP 2 LASTPIN (2300 2750) $PN 173
J 0
(2310 2760);
DISPLAY 0.617021 (2310 2760);
PAINT ORANGE (2310 2760);
FORCEPROP 2 LASTPIN (2300 2700) $PN 176
J 0
(2310 2710);
DISPLAY 0.617021 (2310 2710);
PAINT ORANGE (2310 2710);
FORCEPROP 2 LASTPIN (2300 2650) $PN 178
J 0
(2310 2660);
DISPLAY 0.617021 (2310 2660);
PAINT ORANGE (2310 2660);
FORCEPROP 2 LASTPIN (2300 2600) $PN 180
J 0
(2310 2610);
DISPLAY 0.617021 (2310 2610);
PAINT ORANGE (2310 2610);
FORCEPROP 2 LASTPIN (2300 2550) $PN 182
J 0
(2310 2560);
DISPLAY 0.617021 (2310 2560);
PAINT ORANGE (2310 2560);
FORCEPROP 2 LASTPIN (2300 2500) $PN 184
J 0
(2310 2510);
DISPLAY 0.617021 (2310 2510);
PAINT ORANGE (2310 2510);
FORCEPROP 2 LASTPIN (2300 2450) $PN 187
J 0
(2310 2460);
DISPLAY 0.617021 (2310 2460);
PAINT ORANGE (2310 2460);
FORCEPROP 2 LASTPIN (2300 2400) $PN 189
J 0
(2310 2410);
DISPLAY 0.617021 (2310 2410);
PAINT ORANGE (2310 2410);
FORCEPROP 2 LASTPIN (2300 2350) $PN 191
J 0
(2310 2360);
DISPLAY 0.617021 (2310 2360);
PAINT ORANGE (2310 2360);
FORCEPROP 2 LASTPIN (2300 2300) $PN 193
J 0
(2310 2310);
DISPLAY 0.617021 (2310 2310);
PAINT ORANGE (2310 2310);
FORCEPROP 2 LASTPIN (2300 2250) $PN 195
J 0
(2310 2260);
DISPLAY 0.617021 (2310 2260);
PAINT ORANGE (2310 2260);
FORCEPROP 2 LASTPIN (2300 2200) $PN 198
J 0
(2310 2210);
DISPLAY 0.617021 (2310 2210);
PAINT ORANGE (2310 2210);
FORCEPROP 2 LASTPIN (2300 2150) $PN 200
J 0
(2310 2160);
DISPLAY 0.617021 (2310 2160);
PAINT ORANGE (2310 2160);
FORCEPROP 2 LASTPIN (2300 2100) $PN 202
J 0
(2310 2110);
DISPLAY 0.617021 (2310 2110);
PAINT ORANGE (2310 2110);
FORCEPROP 2 LASTPIN (2300 2050) $PN 239
J 0
(2310 2060);
DISPLAY 0.617021 (2310 2060);
PAINT ORANGE (2310 2060);
FORCEPROP 2 LASTPIN (2300 2000) $PN 241
J 0
(2310 2010);
DISPLAY 0.617021 (2310 2010);
PAINT ORANGE (2310 2010);
FORCEPROP 2 LASTPIN (2300 1900) $PN 246
J 0
(2310 1910);
DISPLAY 0.617021 (2310 1910);
PAINT ORANGE (2310 1910);
FORCEPROP 2 LASTPIN (2300 1850) $PN 248
J 0
(2310 1860);
DISPLAY 0.617021 (2310 1860);
PAINT ORANGE (2310 1860);
FORCEPROP 2 LASTPIN (2300 1800) $PN 250
J 0
(2310 1810);
DISPLAY 0.617021 (2310 1810);
PAINT ORANGE (2310 1810);
FORCEPROP 2 LASTPIN (2300 1750) $PN 252
J 0
(2310 1760);
DISPLAY 0.617021 (2310 1760);
PAINT ORANGE (2310 1760);
FORCEPROP 2 LASTPIN (2300 1700) $PN 254
J 0
(2310 1710);
DISPLAY 0.617021 (2310 1710);
PAINT ORANGE (2310 1710);
FORCEPROP 2 LASTPIN (2300 1650) $PN 257
J 0
(2310 1660);
DISPLAY 0.617021 (2310 1660);
PAINT ORANGE (2310 1660);
FORCEPROP 2 LASTPIN (2300 1600) $PN 259
J 0
(2310 1610);
DISPLAY 0.617021 (2310 1610);
PAINT ORANGE (2310 1610);
FORCEPROP 2 LASTPIN (2300 1550) $PN 261
J 0
(2310 1560);
DISPLAY 0.617021 (2310 1560);
PAINT ORANGE (2310 1560);
FORCEPROP 2 LASTPIN (2300 1500) $PN 263
J 0
(2310 1510);
DISPLAY 0.617021 (2310 1510);
PAINT ORANGE (2310 1510);
FORCEPROP 2 LASTPIN (2300 1450) $PN 265
J 0
(2310 1460);
DISPLAY 0.617021 (2310 1460);
PAINT ORANGE (2310 1460);
FORCEPROP 2 LASTPIN (2300 1400) $PN 268
J 0
(2310 1410);
DISPLAY 0.617021 (2310 1410);
PAINT ORANGE (2310 1410);
FORCEPROP 2 LASTPIN (2300 1350) $PN 270
J 0
(2310 1360);
DISPLAY 0.617021 (2310 1360);
PAINT ORANGE (2310 1360);
FORCEPROP 2 LASTPIN (2300 1300) $PN 272
J 0
(2310 1310);
DISPLAY 0.617021 (2310 1310);
PAINT ORANGE (2310 1310);
FORCEPROP 2 LASTPIN (2300 1250) $PN 274
J 0
(2310 1260);
DISPLAY 0.617021 (2310 1260);
PAINT ORANGE (2310 1260);
FORCEPROP 2 LASTPIN (2300 1200) $PN 276
J 0
(2310 1210);
DISPLAY 0.617021 (2310 1210);
PAINT ORANGE (2310 1210);
FORCEPROP 2 LASTPIN (2300 1150) $PN 279
J 0
(2310 1160);
DISPLAY 0.617021 (2310 1160);
PAINT ORANGE (2310 1160);
FORCEPROP 2 LASTPIN (2300 1100) $PN 281
J 0
(2310 1110);
DISPLAY 0.617021 (2310 1110);
PAINT ORANGE (2310 1110);
FORCEPROP 2 LASTPIN (2300 1050) $PN 283
J 0
(2310 1060);
DISPLAY 0.617021 (2310 1060);
PAINT ORANGE (2310 1060);
FORCEPROP 2 LASTPIN (1300 1850) $PN 103
J 2
(1290 1860);
DISPLAY 0.617021 (1290 1860);
PAINT ORANGE (1290 1860);
FORCEPROP 1 LAST PACK_TYPE PIP
J 0
(1350 3650);
PAINT SKYBLUE (1350 3650);
DISPLAY INVISIBLE (1350 3650);
FORCEPROP 2 LAST BOM_COST MEM
J 0
(1800 2200);
PAINT ORANGE (1800 2200);
DISPLAY INVISIBLE (1800 2200);
FORCEPROP 2 LAST CDS_LIB mstr_sconn
J 0
(1800 2200);
PAINT ORANGE (1800 2200);
DISPLAY INVISIBLE (1800 2200);
FORCEPROP 2 LAST SEC_TYPE PIP
J 0
(1350 3650);
DISPLAY 1.021277 (1350 3650);
PAINT ORANGE (1350 3650);
DISPLAY INVISIBLE (1350 3650);
FORCEPROP 2 LAST SEC 3
J 0
(1350 3650);
DISPLAY 0.680851 (1350 3650);
PAINT MONO (1350 3650);
DISPLAY INVISIBLE (1350 3650);
FORCEPROP 2 LAST CDS_LOCATION J1G1
J 0
(1350 3600);
DISPLAY 0.617021 (1350 3600);
PAINT AQUA (1350 3600);
DISPLAY INVISIBLE (1350 3600);
FORCEPROP 1 LAST PATH I43
J 0
(1800 3550);
PAINT GREEN (1800 3550);
DISPLAY INVISIBLE (1800 3550);
FORCEPROP 2 LAST ROOM DDR4_CH_G
J 0
(1800 2200);
PAINT ORANGE (1800 2200);
DISPLAY INVISIBLE (1800 2200);
FORCEADD GND..1
R 2
(1100 900);
FORCEPROP 3 LASTPIN (1100 950) SIG_NAME GND\g
J 0
(1110 960);
DISPLAY 0.659574 (1110 960);
PAINT MONO (1110 960);
DISPLAY INVISIBLE (1110 960);
FORCEPROP 1 LAST VOLTAGE 0
J 0
(1100 900);
PAINT SKYBLUE (1100 900);
DISPLAY INVISIBLE (1100 900);
FORCEPROP 1 LAST SIZE 1B
J 2
(1025 850);
DISPLAY 1.170213 (1025 850);
PAINT GREEN (1025 850);
DISPLAY INVISIBLE (1025 850);
FORCEPROP 2 LAST CDS_LIB mstr_symbols
J 0
(1100 900);
DISPLAY 0.787234 (1100 900);
PAINT MONO (1100 900);
DISPLAY INVISIBLE (1100 900);
FORCEPROP 2 LAST BOM_COST MEM
J 0
(1100 905);
PAINT ORANGE (1100 905);
DISPLAY INVISIBLE (1100 905);
FORCEPROP 1 LAST BODY_TYPE PLUMBING
J 2
(1145 857);
DISPLAY 0.340426 (1145 857);
PAINT GREEN (1145 857);
DISPLAY INVISIBLE (1145 857);
FORCEPROP 1 LAST PATH I44
J 2
(1025 900);
DISPLAY 0.936170 (1025 900);
PAINT GREEN (1025 900);
DISPLAY INVISIBLE (1025 900);
FORCEPROP 2 LAST ROOM DDR4_CH_G
J 0
(1100 905);
PAINT ORANGE (1100 905);
DISPLAY INVISIBLE (1100 905);
FORCEPROP 1 LAST HDL_POWER GND
J 2
(1100 1050);
DISPLAY 0.553191 (1100 1050);
PAINT GREEN (1100 1050);
DISPLAY INVISIBLE (1100 1050);
FORCEADD OFFPAGE..3
(-1075 4475);
FORCEPROP 2 LAST $XR1 78 
J 0
(-771 4475);
DISPLAY 0.638298 (-771 4475);
PAINT MONO (-771 4475);
FORCEPROP 2 LAST $XR0 57 
J 0
(-861 4475);
DISPLAY 0.638298 (-861 4475);
PAINT MONO (-861 4475);
FORCEPROP 2 LAST CDS_LIB mstr_standard
J 0
(-1075 4475);
DISPLAY 0.787234 (-1075 4475);
PAINT MONO (-1075 4475);
DISPLAY INVISIBLE (-1075 4475);
FORCEPROP 1 LAST OFFPAGE TRUE
J 0
(-750 4350);
DISPLAY 0.936170 (-750 4350);
PAINT GREEN (-750 4350);
DISPLAY INVISIBLE (-750 4350);
FORCEPROP 1 LAST COMMENT_BODY TRUE
J 0
(-1125 4375);
DISPLAY 0.936170 (-1125 4375);
PAINT GREEN (-1125 4375);
DISPLAY INVISIBLE (-1125 4375);
FORCEPROP 2 LAST PATH I45
J 0
(-875 4550);
DISPLAY 0.787234 (-875 4550);
PAINT MONO (-875 4550);
DISPLAY INVISIBLE (-875 4550);
FORCEADD TAP..6
R 2
(-1625 4375);
FORCEPROP 3 LASTPIN (-1675 4375) SIG_NAME M_G_DQ<63>
J 0
(-1665 4385);
DISPLAY 0.659574 (-1665 4385);
PAINT MONO (-1665 4385);
DISPLAY INVISIBLE (-1665 4385);
FORCEPROP 1 LASTPIN (-1675 4375) BN 63
J 2
(-1625 4385);
DISPLAY 0.617021 (-1625 4385);
PAINT PINK (-1625 4385);
FORCEPROP 2 LAST CDS_LIB mstr_standard
J 2
(-1625 4375);
DISPLAY 0.787234 (-1625 4375);
PAINT MONO (-1625 4375);
DISPLAY INVISIBLE (-1625 4375);
FORCEPROP 1 LAST BODY_TYPE PLUMBING
J 2
(-1625 4325);
DISPLAY 1.234043 (-1625 4325);
PAINT GREEN (-1625 4325);
DISPLAY INVISIBLE (-1625 4325);
FORCEPROP 1 LAST HDL_TAP TRUE
J 2
(-1950 4250);
DISPLAY 1.234043 (-1950 4250);
PAINT GREEN (-1950 4250);
DISPLAY INVISIBLE (-1950 4250);
FORCEPROP 1 LAST PATH I46
J 2
(-1625 4375);
DISPLAY 0.936170 (-1625 4375);
PAINT GREEN (-1625 4375);
DISPLAY INVISIBLE (-1625 4375);
FORCEADD TAP..6
R 2
(-1625 4425);
FORCEPROP 3 LASTPIN (-1675 4425) SIG_NAME M_G_DQ<62>
J 0
(-1665 4435);
DISPLAY 0.659574 (-1665 4435);
PAINT MONO (-1665 4435);
DISPLAY INVISIBLE (-1665 4435);
FORCEPROP 1 LASTPIN (-1675 4425) BN 62
J 2
(-1625 4435);
DISPLAY 0.617021 (-1625 4435);
PAINT PINK (-1625 4435);
FORCEPROP 2 LAST CDS_LIB mstr_standard
J 2
(-1625 4425);
DISPLAY 0.787234 (-1625 4425);
PAINT MONO (-1625 4425);
DISPLAY INVISIBLE (-1625 4425);
FORCEPROP 1 LAST BODY_TYPE PLUMBING
J 2
(-1625 4375);
DISPLAY 1.234043 (-1625 4375);
PAINT GREEN (-1625 4375);
DISPLAY INVISIBLE (-1625 4375);
FORCEPROP 1 LAST HDL_TAP TRUE
J 2
(-1950 4300);
DISPLAY 1.234043 (-1950 4300);
PAINT GREEN (-1950 4300);
DISPLAY INVISIBLE (-1950 4300);
FORCEPROP 1 LAST PATH I47
J 2
(-1625 4425);
DISPLAY 0.936170 (-1625 4425);
PAINT GREEN (-1625 4425);
DISPLAY INVISIBLE (-1625 4425);
FORCEADD TAP..6
R 2
(-1625 4275);
FORCEPROP 3 LASTPIN (-1675 4275) SIG_NAME M_G_DQ<61>
J 0
(-1665 4285);
DISPLAY 0.659574 (-1665 4285);
PAINT MONO (-1665 4285);
DISPLAY INVISIBLE (-1665 4285);
FORCEPROP 1 LASTPIN (-1675 4275) BN 61
J 2
(-1625 4285);
DISPLAY 0.617021 (-1625 4285);
PAINT PINK (-1625 4285);
FORCEPROP 2 LAST CDS_LIB mstr_standard
J 2
(-1625 4275);
DISPLAY 0.787234 (-1625 4275);
PAINT MONO (-1625 4275);
DISPLAY INVISIBLE (-1625 4275);
FORCEPROP 1 LAST BODY_TYPE PLUMBING
J 2
(-1625 4225);
DISPLAY 1.234043 (-1625 4225);
PAINT GREEN (-1625 4225);
DISPLAY INVISIBLE (-1625 4225);
FORCEPROP 1 LAST HDL_TAP TRUE
J 2
(-1950 4150);
DISPLAY 1.234043 (-1950 4150);
PAINT GREEN (-1950 4150);
DISPLAY INVISIBLE (-1950 4150);
FORCEPROP 1 LAST PATH I48
J 2
(-1625 4275);
DISPLAY 0.936170 (-1625 4275);
PAINT GREEN (-1625 4275);
DISPLAY INVISIBLE (-1625 4275);
FORCEADD TAP..6
R 2
(-1625 4325);
FORCEPROP 3 LASTPIN (-1675 4325) SIG_NAME M_G_DQ<60>
J 0
(-1665 4335);
DISPLAY 0.659574 (-1665 4335);
PAINT MONO (-1665 4335);
DISPLAY INVISIBLE (-1665 4335);
FORCEPROP 1 LASTPIN (-1675 4325) BN 60
J 2
(-1625 4335);
DISPLAY 0.617021 (-1625 4335);
PAINT PINK (-1625 4335);
FORCEPROP 2 LAST CDS_LIB mstr_standard
J 2
(-1625 4325);
DISPLAY 0.787234 (-1625 4325);
PAINT MONO (-1625 4325);
DISPLAY INVISIBLE (-1625 4325);
FORCEPROP 1 LAST BODY_TYPE PLUMBING
J 2
(-1625 4275);
DISPLAY 1.234043 (-1625 4275);
PAINT GREEN (-1625 4275);
DISPLAY INVISIBLE (-1625 4275);
FORCEPROP 1 LAST HDL_TAP TRUE
J 2
(-1950 4200);
DISPLAY 1.234043 (-1950 4200);
PAINT GREEN (-1950 4200);
DISPLAY INVISIBLE (-1950 4200);
FORCEPROP 1 LAST PATH I49
J 2
(-1625 4325);
DISPLAY 0.936170 (-1625 4325);
PAINT GREEN (-1625 4325);
DISPLAY INVISIBLE (-1625 4325);
FORCEADD TAP..6
R 2
(900 4800);
FORCEPROP 3 LASTPIN (850 4800) SIG_NAME M_G_DQS_DN<15>
J 0
(860 4810);
DISPLAY 0.659574 (860 4810);
PAINT MONO (860 4810);
DISPLAY INVISIBLE (860 4810);
FORCEPROP 1 LASTPIN (850 4800) BN 15
J 2
(900 4810);
DISPLAY 0.617021 (900 4810);
PAINT PINK (900 4810);
FORCEPROP 2 LAST CDS_LIB mstr_standard
J 0
(900 4800);
DISPLAY 0.787234 (900 4800);
PAINT MONO (900 4800);
DISPLAY INVISIBLE (900 4800);
FORCEPROP 1 LAST BODY_TYPE PLUMBING
J 2
(900 4750);
DISPLAY 1.234043 (900 4750);
PAINT GREEN (900 4750);
DISPLAY INVISIBLE (900 4750);
FORCEPROP 1 LAST HDL_TAP TRUE
J 2
(575 4675);
DISPLAY 1.234043 (575 4675);
PAINT GREEN (575 4675);
DISPLAY INVISIBLE (575 4675);
FORCEPROP 1 LAST PATH I5
J 2
(900 4800);
DISPLAY 0.936170 (900 4800);
PAINT GREEN (900 4800);
DISPLAY INVISIBLE (900 4800);
FORCEADD TAP..6
R 2
(-1625 4225);
FORCEPROP 3 LASTPIN (-1675 4225) SIG_NAME M_G_DQ<58>
J 0
(-1665 4235);
DISPLAY 0.659574 (-1665 4235);
PAINT MONO (-1665 4235);
DISPLAY INVISIBLE (-1665 4235);
FORCEPROP 1 LASTPIN (-1675 4225) BN 58
J 2
(-1625 4235);
DISPLAY 0.617021 (-1625 4235);
PAINT PINK (-1625 4235);
FORCEPROP 2 LAST CDS_LIB mstr_standard
J 2
(-1625 4225);
DISPLAY 0.787234 (-1625 4225);
PAINT MONO (-1625 4225);
DISPLAY INVISIBLE (-1625 4225);
FORCEPROP 1 LAST BODY_TYPE PLUMBING
J 2
(-1625 4175);
DISPLAY 1.234043 (-1625 4175);
PAINT GREEN (-1625 4175);
DISPLAY INVISIBLE (-1625 4175);
FORCEPROP 1 LAST HDL_TAP TRUE
J 2
(-1950 4100);
DISPLAY 1.234043 (-1950 4100);
PAINT GREEN (-1950 4100);
DISPLAY INVISIBLE (-1950 4100);
FORCEPROP 1 LAST PATH I50
J 2
(-1625 4225);
DISPLAY 0.936170 (-1625 4225);
PAINT GREEN (-1625 4225);
DISPLAY INVISIBLE (-1625 4225);
FORCEADD TAP..6
R 2
(-1625 4175);
FORCEPROP 3 LASTPIN (-1675 4175) SIG_NAME M_G_DQ<59>
J 0
(-1665 4185);
DISPLAY 0.659574 (-1665 4185);
PAINT MONO (-1665 4185);
DISPLAY INVISIBLE (-1665 4185);
FORCEPROP 1 LASTPIN (-1675 4175) BN 59
J 2
(-1625 4185);
DISPLAY 0.617021 (-1625 4185);
PAINT PINK (-1625 4185);
FORCEPROP 2 LAST CDS_LIB mstr_standard
J 2
(-1625 4175);
DISPLAY 0.787234 (-1625 4175);
PAINT MONO (-1625 4175);
DISPLAY INVISIBLE (-1625 4175);
FORCEPROP 1 LAST BODY_TYPE PLUMBING
J 2
(-1625 4125);
DISPLAY 1.234043 (-1625 4125);
PAINT GREEN (-1625 4125);
DISPLAY INVISIBLE (-1625 4125);
FORCEPROP 1 LAST HDL_TAP TRUE
J 2
(-1950 4050);
DISPLAY 1.234043 (-1950 4050);
PAINT GREEN (-1950 4050);
DISPLAY INVISIBLE (-1950 4050);
FORCEPROP 1 LAST PATH I51
J 2
(-1625 4175);
DISPLAY 0.936170 (-1625 4175);
PAINT GREEN (-1625 4175);
DISPLAY INVISIBLE (-1625 4175);
FORCEADD TAP..6
R 2
(-1625 4125);
FORCEPROP 3 LASTPIN (-1675 4125) SIG_NAME M_G_DQ<56>
J 0
(-1665 4135);
DISPLAY 0.659574 (-1665 4135);
PAINT MONO (-1665 4135);
DISPLAY INVISIBLE (-1665 4135);
FORCEPROP 1 LASTPIN (-1675 4125) BN 56
J 2
(-1625 4135);
DISPLAY 0.617021 (-1625 4135);
PAINT PINK (-1625 4135);
FORCEPROP 2 LAST CDS_LIB mstr_standard
J 2
(-1625 4125);
DISPLAY 0.787234 (-1625 4125);
PAINT MONO (-1625 4125);
DISPLAY INVISIBLE (-1625 4125);
FORCEPROP 1 LAST BODY_TYPE PLUMBING
J 2
(-1625 4075);
DISPLAY 1.234043 (-1625 4075);
PAINT GREEN (-1625 4075);
DISPLAY INVISIBLE (-1625 4075);
FORCEPROP 1 LAST HDL_TAP TRUE
J 2
(-1950 4000);
DISPLAY 1.234043 (-1950 4000);
PAINT GREEN (-1950 4000);
DISPLAY INVISIBLE (-1950 4000);
FORCEPROP 1 LAST PATH I52
J 2
(-1625 4125);
DISPLAY 0.936170 (-1625 4125);
PAINT GREEN (-1625 4125);
DISPLAY INVISIBLE (-1625 4125);
FORCEADD TAP..6
R 2
(-1625 4075);
FORCEPROP 3 LASTPIN (-1675 4075) SIG_NAME M_G_DQ<57>
J 0
(-1665 4085);
DISPLAY 0.659574 (-1665 4085);
PAINT MONO (-1665 4085);
DISPLAY INVISIBLE (-1665 4085);
FORCEPROP 1 LASTPIN (-1675 4075) BN 57
J 2
(-1625 4085);
DISPLAY 0.617021 (-1625 4085);
PAINT PINK (-1625 4085);
FORCEPROP 2 LAST CDS_LIB mstr_standard
J 2
(-1625 4075);
DISPLAY 0.787234 (-1625 4075);
PAINT MONO (-1625 4075);
DISPLAY INVISIBLE (-1625 4075);
FORCEPROP 1 LAST BODY_TYPE PLUMBING
J 2
(-1625 4025);
DISPLAY 1.234043 (-1625 4025);
PAINT GREEN (-1625 4025);
DISPLAY INVISIBLE (-1625 4025);
FORCEPROP 1 LAST HDL_TAP TRUE
J 2
(-1950 3950);
DISPLAY 1.234043 (-1950 3950);
PAINT GREEN (-1950 3950);
DISPLAY INVISIBLE (-1950 3950);
FORCEPROP 1 LAST PATH I53
J 2
(-1625 4075);
DISPLAY 0.936170 (-1625 4075);
PAINT GREEN (-1625 4075);
DISPLAY INVISIBLE (-1625 4075);
FORCEADD TAP..6
R 2
(-1625 4025);
FORCEPROP 3 LASTPIN (-1675 4025) SIG_NAME M_G_DQ<54>
J 0
(-1665 4035);
DISPLAY 0.659574 (-1665 4035);
PAINT MONO (-1665 4035);
DISPLAY INVISIBLE (-1665 4035);
FORCEPROP 1 LASTPIN (-1675 4025) BN 54
J 2
(-1625 4035);
DISPLAY 0.617021 (-1625 4035);
PAINT PINK (-1625 4035);
FORCEPROP 2 LAST CDS_LIB mstr_standard
J 2
(-1625 4025);
DISPLAY 0.787234 (-1625 4025);
PAINT MONO (-1625 4025);
DISPLAY INVISIBLE (-1625 4025);
FORCEPROP 1 LAST BODY_TYPE PLUMBING
J 2
(-1625 3975);
DISPLAY 1.234043 (-1625 3975);
PAINT GREEN (-1625 3975);
DISPLAY INVISIBLE (-1625 3975);
FORCEPROP 1 LAST HDL_TAP TRUE
J 2
(-1950 3900);
DISPLAY 1.234043 (-1950 3900);
PAINT GREEN (-1950 3900);
DISPLAY INVISIBLE (-1950 3900);
FORCEPROP 1 LAST PATH I54
J 2
(-1625 4025);
DISPLAY 0.936170 (-1625 4025);
PAINT GREEN (-1625 4025);
DISPLAY INVISIBLE (-1625 4025);
FORCEADD TAP..6
R 2
(-1625 3875);
FORCEPROP 3 LASTPIN (-1675 3875) SIG_NAME M_G_DQ<53>
J 0
(-1665 3885);
DISPLAY 0.659574 (-1665 3885);
PAINT MONO (-1665 3885);
DISPLAY INVISIBLE (-1665 3885);
FORCEPROP 1 LASTPIN (-1675 3875) BN 53
J 2
(-1625 3885);
DISPLAY 0.617021 (-1625 3885);
PAINT PINK (-1625 3885);
FORCEPROP 2 LAST CDS_LIB mstr_standard
J 2
(-1625 3875);
DISPLAY 0.787234 (-1625 3875);
PAINT MONO (-1625 3875);
DISPLAY INVISIBLE (-1625 3875);
FORCEPROP 1 LAST BODY_TYPE PLUMBING
J 2
(-1625 3825);
DISPLAY 1.234043 (-1625 3825);
PAINT GREEN (-1625 3825);
DISPLAY INVISIBLE (-1625 3825);
FORCEPROP 1 LAST HDL_TAP TRUE
J 2
(-1950 3750);
DISPLAY 1.234043 (-1950 3750);
PAINT GREEN (-1950 3750);
DISPLAY INVISIBLE (-1950 3750);
FORCEPROP 1 LAST PATH I55
J 2
(-1625 3875);
DISPLAY 0.936170 (-1625 3875);
PAINT GREEN (-1625 3875);
DISPLAY INVISIBLE (-1625 3875);
FORCEADD TAP..6
R 2
(-1625 3975);
FORCEPROP 3 LASTPIN (-1675 3975) SIG_NAME M_G_DQ<55>
J 0
(-1665 3985);
DISPLAY 0.659574 (-1665 3985);
PAINT MONO (-1665 3985);
DISPLAY INVISIBLE (-1665 3985);
FORCEPROP 1 LASTPIN (-1675 3975) BN 55
J 2
(-1625 3985);
DISPLAY 0.617021 (-1625 3985);
PAINT PINK (-1625 3985);
FORCEPROP 2 LAST CDS_LIB mstr_standard
J 2
(-1625 3975);
DISPLAY 0.787234 (-1625 3975);
PAINT MONO (-1625 3975);
DISPLAY INVISIBLE (-1625 3975);
FORCEPROP 1 LAST BODY_TYPE PLUMBING
J 2
(-1625 3925);
DISPLAY 1.234043 (-1625 3925);
PAINT GREEN (-1625 3925);
DISPLAY INVISIBLE (-1625 3925);
FORCEPROP 1 LAST HDL_TAP TRUE
J 2
(-1950 3850);
DISPLAY 1.234043 (-1950 3850);
PAINT GREEN (-1950 3850);
DISPLAY INVISIBLE (-1950 3850);
FORCEPROP 1 LAST PATH I56
J 2
(-1625 3975);
DISPLAY 0.936170 (-1625 3975);
PAINT GREEN (-1625 3975);
DISPLAY INVISIBLE (-1625 3975);
FORCEADD TAP..6
R 2
(-1625 3925);
FORCEPROP 3 LASTPIN (-1675 3925) SIG_NAME M_G_DQ<52>
J 0
(-1665 3935);
DISPLAY 0.659574 (-1665 3935);
PAINT MONO (-1665 3935);
DISPLAY INVISIBLE (-1665 3935);
FORCEPROP 1 LASTPIN (-1675 3925) BN 52
J 2
(-1625 3935);
DISPLAY 0.617021 (-1625 3935);
PAINT PINK (-1625 3935);
FORCEPROP 2 LAST CDS_LIB mstr_standard
J 2
(-1625 3925);
DISPLAY 0.787234 (-1625 3925);
PAINT MONO (-1625 3925);
DISPLAY INVISIBLE (-1625 3925);
FORCEPROP 1 LAST BODY_TYPE PLUMBING
J 2
(-1625 3875);
DISPLAY 1.234043 (-1625 3875);
PAINT GREEN (-1625 3875);
DISPLAY INVISIBLE (-1625 3875);
FORCEPROP 1 LAST HDL_TAP TRUE
J 2
(-1950 3800);
DISPLAY 1.234043 (-1950 3800);
PAINT GREEN (-1950 3800);
DISPLAY INVISIBLE (-1950 3800);
FORCEPROP 1 LAST PATH I57
J 2
(-1625 3925);
DISPLAY 0.936170 (-1625 3925);
PAINT GREEN (-1625 3925);
DISPLAY INVISIBLE (-1625 3925);
FORCEADD TAP..6
R 2
(-1625 3825);
FORCEPROP 3 LASTPIN (-1675 3825) SIG_NAME M_G_DQ<50>
J 0
(-1665 3835);
DISPLAY 0.659574 (-1665 3835);
PAINT MONO (-1665 3835);
DISPLAY INVISIBLE (-1665 3835);
FORCEPROP 1 LASTPIN (-1675 3825) BN 50
J 2
(-1625 3835);
DISPLAY 0.617021 (-1625 3835);
PAINT PINK (-1625 3835);
FORCEPROP 2 LAST CDS_LIB mstr_standard
J 2
(-1625 3825);
DISPLAY 0.787234 (-1625 3825);
PAINT MONO (-1625 3825);
DISPLAY INVISIBLE (-1625 3825);
FORCEPROP 1 LAST BODY_TYPE PLUMBING
J 2
(-1625 3775);
DISPLAY 1.234043 (-1625 3775);
PAINT GREEN (-1625 3775);
DISPLAY INVISIBLE (-1625 3775);
FORCEPROP 1 LAST HDL_TAP TRUE
J 2
(-1950 3700);
DISPLAY 1.234043 (-1950 3700);
PAINT GREEN (-1950 3700);
DISPLAY INVISIBLE (-1950 3700);
FORCEPROP 1 LAST PATH I58
J 2
(-1625 3825);
DISPLAY 0.936170 (-1625 3825);
PAINT GREEN (-1625 3825);
DISPLAY INVISIBLE (-1625 3825);
FORCEADD TAP..6
R 2
(-1625 3775);
FORCEPROP 3 LASTPIN (-1675 3775) SIG_NAME M_G_DQ<51>
J 0
(-1665 3785);
DISPLAY 0.659574 (-1665 3785);
PAINT MONO (-1665 3785);
DISPLAY INVISIBLE (-1665 3785);
FORCEPROP 1 LASTPIN (-1675 3775) BN 51
J 2
(-1625 3785);
DISPLAY 0.617021 (-1625 3785);
PAINT PINK (-1625 3785);
FORCEPROP 2 LAST CDS_LIB mstr_standard
J 2
(-1625 3775);
DISPLAY 0.787234 (-1625 3775);
PAINT MONO (-1625 3775);
DISPLAY INVISIBLE (-1625 3775);
FORCEPROP 1 LAST BODY_TYPE PLUMBING
J 2
(-1625 3725);
DISPLAY 1.234043 (-1625 3725);
PAINT GREEN (-1625 3725);
DISPLAY INVISIBLE (-1625 3725);
FORCEPROP 1 LAST HDL_TAP TRUE
J 2
(-1950 3650);
DISPLAY 1.234043 (-1950 3650);
PAINT GREEN (-1950 3650);
DISPLAY INVISIBLE (-1950 3650);
FORCEPROP 1 LAST PATH I59
J 2
(-1625 3775);
DISPLAY 0.936170 (-1625 3775);
PAINT GREEN (-1625 3775);
DISPLAY INVISIBLE (-1625 3775);
FORCEADD TAP..6
R 2
(900 4900);
FORCEPROP 3 LASTPIN (850 4900) SIG_NAME M_G_DQS_DN<16>
J 0
(860 4910);
DISPLAY 0.659574 (860 4910);
PAINT MONO (860 4910);
DISPLAY INVISIBLE (860 4910);
FORCEPROP 1 LASTPIN (850 4900) BN 16
J 2
(900 4910);
DISPLAY 0.617021 (900 4910);
PAINT PINK (900 4910);
FORCEPROP 2 LAST CDS_LIB mstr_standard
J 0
(900 4900);
DISPLAY 0.787234 (900 4900);
PAINT MONO (900 4900);
DISPLAY INVISIBLE (900 4900);
FORCEPROP 1 LAST BODY_TYPE PLUMBING
J 2
(900 4850);
DISPLAY 1.234043 (900 4850);
PAINT GREEN (900 4850);
DISPLAY INVISIBLE (900 4850);
FORCEPROP 1 LAST HDL_TAP TRUE
J 2
(575 4775);
DISPLAY 1.234043 (575 4775);
PAINT GREEN (575 4775);
DISPLAY INVISIBLE (575 4775);
FORCEPROP 1 LAST PATH I6
J 2
(900 4900);
DISPLAY 0.936170 (900 4900);
PAINT GREEN (900 4900);
DISPLAY INVISIBLE (900 4900);
FORCEADD TAP..6
R 2
(-1625 3725);
FORCEPROP 3 LASTPIN (-1675 3725) SIG_NAME M_G_DQ<48>
J 0
(-1665 3735);
DISPLAY 0.659574 (-1665 3735);
PAINT MONO (-1665 3735);
DISPLAY INVISIBLE (-1665 3735);
FORCEPROP 1 LASTPIN (-1675 3725) BN 48
J 2
(-1625 3735);
DISPLAY 0.617021 (-1625 3735);
PAINT PINK (-1625 3735);
FORCEPROP 2 LAST CDS_LIB mstr_standard
J 2
(-1625 3725);
DISPLAY 0.787234 (-1625 3725);
PAINT MONO (-1625 3725);
DISPLAY INVISIBLE (-1625 3725);
FORCEPROP 1 LAST BODY_TYPE PLUMBING
J 2
(-1625 3675);
DISPLAY 1.234043 (-1625 3675);
PAINT GREEN (-1625 3675);
DISPLAY INVISIBLE (-1625 3675);
FORCEPROP 1 LAST HDL_TAP TRUE
J 2
(-1950 3600);
DISPLAY 1.234043 (-1950 3600);
PAINT GREEN (-1950 3600);
DISPLAY INVISIBLE (-1950 3600);
FORCEPROP 1 LAST PATH I60
J 2
(-1625 3725);
DISPLAY 0.936170 (-1625 3725);
PAINT GREEN (-1625 3725);
DISPLAY INVISIBLE (-1625 3725);
FORCEADD TAP..6
R 2
(-1625 3575);
FORCEPROP 3 LASTPIN (-1675 3575) SIG_NAME M_G_DQ<47>
J 0
(-1665 3585);
DISPLAY 0.659574 (-1665 3585);
PAINT MONO (-1665 3585);
DISPLAY INVISIBLE (-1665 3585);
FORCEPROP 1 LASTPIN (-1675 3575) BN 47
J 2
(-1625 3585);
DISPLAY 0.617021 (-1625 3585);
PAINT PINK (-1625 3585);
FORCEPROP 2 LAST CDS_LIB mstr_standard
J 2
(-1625 3575);
DISPLAY 0.787234 (-1625 3575);
PAINT MONO (-1625 3575);
DISPLAY INVISIBLE (-1625 3575);
FORCEPROP 1 LAST BODY_TYPE PLUMBING
J 2
(-1625 3525);
DISPLAY 1.234043 (-1625 3525);
PAINT GREEN (-1625 3525);
DISPLAY INVISIBLE (-1625 3525);
FORCEPROP 1 LAST HDL_TAP TRUE
J 2
(-1950 3450);
DISPLAY 1.234043 (-1950 3450);
PAINT GREEN (-1950 3450);
DISPLAY INVISIBLE (-1950 3450);
FORCEPROP 1 LAST PATH I61
J 2
(-1625 3575);
DISPLAY 0.936170 (-1625 3575);
PAINT GREEN (-1625 3575);
DISPLAY INVISIBLE (-1625 3575);
FORCEADD TAP..6
R 2
(-1625 3675);
FORCEPROP 3 LASTPIN (-1675 3675) SIG_NAME M_G_DQ<49>
J 0
(-1665 3685);
DISPLAY 0.659574 (-1665 3685);
PAINT MONO (-1665 3685);
DISPLAY INVISIBLE (-1665 3685);
FORCEPROP 1 LASTPIN (-1675 3675) BN 49
J 2
(-1625 3685);
DISPLAY 0.617021 (-1625 3685);
PAINT PINK (-1625 3685);
FORCEPROP 2 LAST CDS_LIB mstr_standard
J 2
(-1625 3675);
DISPLAY 0.787234 (-1625 3675);
PAINT MONO (-1625 3675);
DISPLAY INVISIBLE (-1625 3675);
FORCEPROP 1 LAST BODY_TYPE PLUMBING
J 2
(-1625 3625);
DISPLAY 1.234043 (-1625 3625);
PAINT GREEN (-1625 3625);
DISPLAY INVISIBLE (-1625 3625);
FORCEPROP 1 LAST HDL_TAP TRUE
J 2
(-1950 3550);
DISPLAY 1.234043 (-1950 3550);
PAINT GREEN (-1950 3550);
DISPLAY INVISIBLE (-1950 3550);
FORCEPROP 1 LAST PATH I62
J 2
(-1625 3675);
DISPLAY 0.936170 (-1625 3675);
PAINT GREEN (-1625 3675);
DISPLAY INVISIBLE (-1625 3675);
FORCEADD TAP..6
R 2
(-1625 3625);
FORCEPROP 3 LASTPIN (-1675 3625) SIG_NAME M_G_DQ<46>
J 0
(-1665 3635);
DISPLAY 0.659574 (-1665 3635);
PAINT MONO (-1665 3635);
DISPLAY INVISIBLE (-1665 3635);
FORCEPROP 1 LASTPIN (-1675 3625) BN 46
J 2
(-1625 3635);
DISPLAY 0.617021 (-1625 3635);
PAINT PINK (-1625 3635);
FORCEPROP 2 LAST CDS_LIB mstr_standard
J 2
(-1625 3625);
DISPLAY 0.787234 (-1625 3625);
PAINT MONO (-1625 3625);
DISPLAY INVISIBLE (-1625 3625);
FORCEPROP 1 LAST BODY_TYPE PLUMBING
J 2
(-1625 3575);
DISPLAY 1.234043 (-1625 3575);
PAINT GREEN (-1625 3575);
DISPLAY INVISIBLE (-1625 3575);
FORCEPROP 1 LAST HDL_TAP TRUE
J 2
(-1950 3500);
DISPLAY 1.234043 (-1950 3500);
PAINT GREEN (-1950 3500);
DISPLAY INVISIBLE (-1950 3500);
FORCEPROP 1 LAST PATH I63
J 2
(-1625 3625);
DISPLAY 0.936170 (-1625 3625);
PAINT GREEN (-1625 3625);
DISPLAY INVISIBLE (-1625 3625);
FORCEADD TAP..6
R 2
(-1625 3525);
FORCEPROP 3 LASTPIN (-1675 3525) SIG_NAME M_G_DQ<44>
J 0
(-1665 3535);
DISPLAY 0.659574 (-1665 3535);
PAINT MONO (-1665 3535);
DISPLAY INVISIBLE (-1665 3535);
FORCEPROP 1 LASTPIN (-1675 3525) BN 44
J 2
(-1625 3535);
DISPLAY 0.617021 (-1625 3535);
PAINT PINK (-1625 3535);
FORCEPROP 2 LAST CDS_LIB mstr_standard
J 2
(-1625 3525);
DISPLAY 0.787234 (-1625 3525);
PAINT MONO (-1625 3525);
DISPLAY INVISIBLE (-1625 3525);
FORCEPROP 1 LAST BODY_TYPE PLUMBING
J 2
(-1625 3475);
DISPLAY 1.234043 (-1625 3475);
PAINT GREEN (-1625 3475);
DISPLAY INVISIBLE (-1625 3475);
FORCEPROP 1 LAST HDL_TAP TRUE
J 2
(-1950 3400);
DISPLAY 1.234043 (-1950 3400);
PAINT GREEN (-1950 3400);
DISPLAY INVISIBLE (-1950 3400);
FORCEPROP 1 LAST PATH I64
J 2
(-1625 3525);
DISPLAY 0.936170 (-1625 3525);
PAINT GREEN (-1625 3525);
DISPLAY INVISIBLE (-1625 3525);
FORCEADD TAP..6
R 2
(-1625 3475);
FORCEPROP 3 LASTPIN (-1675 3475) SIG_NAME M_G_DQ<45>
J 0
(-1665 3485);
DISPLAY 0.659574 (-1665 3485);
PAINT MONO (-1665 3485);
DISPLAY INVISIBLE (-1665 3485);
FORCEPROP 1 LASTPIN (-1675 3475) BN 45
J 2
(-1625 3485);
DISPLAY 0.617021 (-1625 3485);
PAINT PINK (-1625 3485);
FORCEPROP 2 LAST CDS_LIB mstr_standard
J 2
(-1625 3475);
DISPLAY 0.787234 (-1625 3475);
PAINT MONO (-1625 3475);
DISPLAY INVISIBLE (-1625 3475);
FORCEPROP 1 LAST BODY_TYPE PLUMBING
J 2
(-1625 3425);
DISPLAY 1.234043 (-1625 3425);
PAINT GREEN (-1625 3425);
DISPLAY INVISIBLE (-1625 3425);
FORCEPROP 1 LAST HDL_TAP TRUE
J 2
(-1950 3350);
DISPLAY 1.234043 (-1950 3350);
PAINT GREEN (-1950 3350);
DISPLAY INVISIBLE (-1950 3350);
FORCEPROP 1 LAST PATH I65
J 2
(-1625 3475);
DISPLAY 0.936170 (-1625 3475);
PAINT GREEN (-1625 3475);
DISPLAY INVISIBLE (-1625 3475);
FORCEADD SCONN288_H44441004..2
(0 4200);
FORCEPROP 1 LAST LOCATION J1G1
J 0
(-400 5300);
DISPLAY 0.617021 (-400 5300);
PAINT AQUA (-400 5300);
FORCEPROP 1 LAST PART_NUMBER H44441-004
J 0
(-400 3100);
DISPLAY 0.617021 (-400 3100);
PAINT BLUE (-400 3100);
FORCEPROP 1 LAST MATERIAL SCONN
J 0
(-400 5250);
DISPLAY 0.617021 (-400 5250);
PAINT SKYBLUE (-400 5250);
FORCEPROP 2 LASTPIN (450 5050) $PN 51
J 0
(460 5060);
DISPLAY 0.617021 (460 5060);
PAINT ORANGE (460 5060);
FORCEPROP 2 LASTPIN (450 5000) $PN 52
J 0
(460 5010);
DISPLAY 0.617021 (460 5010);
PAINT ORANGE (460 5010);
FORCEPROP 2 LASTPIN (450 4950) $PN 132
J 0
(460 4960);
DISPLAY 0.617021 (460 4960);
PAINT ORANGE (460 4960);
FORCEPROP 2 LASTPIN (450 4900) $PN 133
J 0
(460 4910);
DISPLAY 0.617021 (460 4910);
PAINT ORANGE (460 4910);
FORCEPROP 2 LASTPIN (450 4850) $PN 121
J 0
(460 4860);
DISPLAY 0.617021 (460 4860);
PAINT ORANGE (460 4860);
FORCEPROP 2 LASTPIN (450 4800) $PN 122
J 0
(460 4810);
DISPLAY 0.617021 (460 4810);
PAINT ORANGE (460 4810);
FORCEPROP 2 LASTPIN (450 4750) $PN 110
J 0
(460 4760);
DISPLAY 0.617021 (460 4760);
PAINT ORANGE (460 4760);
FORCEPROP 2 LASTPIN (450 4700) $PN 111
J 0
(460 4710);
DISPLAY 0.617021 (460 4710);
PAINT ORANGE (460 4710);
FORCEPROP 2 LASTPIN (450 4650) $PN 99
J 0
(460 4660);
DISPLAY 0.617021 (460 4660);
PAINT ORANGE (460 4660);
FORCEPROP 2 LASTPIN (450 4600) $PN 100
J 0
(460 4610);
DISPLAY 0.617021 (460 4610);
PAINT ORANGE (460 4610);
FORCEPROP 2 LASTPIN (450 4550) $PN 40
J 0
(460 4560);
DISPLAY 0.617021 (460 4560);
PAINT ORANGE (460 4560);
FORCEPROP 2 LASTPIN (450 4500) $PN 41
J 0
(460 4510);
DISPLAY 0.617021 (460 4510);
PAINT ORANGE (460 4510);
FORCEPROP 2 LASTPIN (450 4450) $PN 29
J 0
(460 4460);
DISPLAY 0.617021 (460 4460);
PAINT ORANGE (460 4460);
FORCEPROP 2 LASTPIN (450 4400) $PN 30
J 0
(460 4410);
DISPLAY 0.617021 (460 4410);
PAINT ORANGE (460 4410);
FORCEPROP 2 LASTPIN (450 4350) $PN 18
J 0
(460 4360);
DISPLAY 0.617021 (460 4360);
PAINT ORANGE (460 4360);
FORCEPROP 2 LASTPIN (450 4300) $PN 19
J 0
(460 4310);
DISPLAY 0.617021 (460 4310);
PAINT ORANGE (460 4310);
FORCEPROP 2 LASTPIN (450 4250) $PN 7
J 0
(460 4260);
DISPLAY 0.617021 (460 4260);
PAINT ORANGE (460 4260);
FORCEPROP 2 LASTPIN (450 4200) $PN 8
J 0
(460 4210);
DISPLAY 0.617021 (460 4210);
PAINT ORANGE (460 4210);
FORCEPROP 2 LASTPIN (450 4150) $PN 197
J 0
(460 4160);
DISPLAY 0.617021 (460 4160);
PAINT ORANGE (460 4160);
FORCEPROP 2 LASTPIN (450 4100) $PN 196
J 0
(460 4110);
DISPLAY 0.617021 (460 4110);
PAINT ORANGE (460 4110);
FORCEPROP 2 LASTPIN (450 4050) $PN 278
J 0
(460 4060);
DISPLAY 0.617021 (460 4060);
PAINT ORANGE (460 4060);
FORCEPROP 2 LASTPIN (450 4000) $PN 277
J 0
(460 4010);
DISPLAY 0.617021 (460 4010);
PAINT ORANGE (460 4010);
FORCEPROP 2 LASTPIN (450 3950) $PN 267
J 0
(460 3960);
DISPLAY 0.617021 (460 3960);
PAINT ORANGE (460 3960);
FORCEPROP 2 LASTPIN (450 3850) $PN 256
J 0
(460 3860);
DISPLAY 0.617021 (460 3860);
PAINT ORANGE (460 3860);
FORCEPROP 2 LASTPIN (450 3800) $PN 255
J 0
(460 3810);
DISPLAY 0.617021 (460 3810);
PAINT ORANGE (460 3810);
FORCEPROP 2 LASTPIN (450 3750) $PN 245
J 0
(460 3760);
DISPLAY 0.617021 (460 3760);
PAINT ORANGE (460 3760);
FORCEPROP 2 LASTPIN (450 3700) $PN 244
J 0
(460 3710);
DISPLAY 0.617021 (460 3710);
PAINT ORANGE (460 3710);
FORCEPROP 2 LASTPIN (450 3650) $PN 186
J 0
(460 3660);
DISPLAY 0.617021 (460 3660);
PAINT ORANGE (460 3660);
FORCEPROP 2 LASTPIN (450 3600) $PN 185
J 0
(460 3610);
DISPLAY 0.617021 (460 3610);
PAINT ORANGE (460 3610);
FORCEPROP 2 LASTPIN (450 3550) $PN 175
J 0
(460 3560);
DISPLAY 0.617021 (460 3560);
PAINT ORANGE (460 3560);
FORCEPROP 2 LASTPIN (450 3500) $PN 174
J 0
(460 3510);
DISPLAY 0.617021 (460 3510);
PAINT ORANGE (460 3510);
FORCEPROP 2 LASTPIN (450 3450) $PN 164
J 0
(460 3460);
DISPLAY 0.617021 (460 3460);
PAINT ORANGE (460 3460);
FORCEPROP 2 LASTPIN (450 3400) $PN 163
J 0
(460 3410);
DISPLAY 0.617021 (460 3410);
PAINT ORANGE (460 3410);
FORCEPROP 2 LASTPIN (450 3350) $PN 153
J 0
(460 3360);
DISPLAY 0.617021 (460 3360);
PAINT ORANGE (460 3360);
FORCEPROP 2 LASTPIN (450 3300) $PN 152
J 0
(460 3310);
DISPLAY 0.617021 (460 3310);
PAINT ORANGE (460 3310);
FORCEPROP 2 LASTPIN (450 3900) $PN 266
J 0
(460 3910);
DISPLAY 0.617021 (460 3910);
PAINT ORANGE (460 3910);
FORCEPROP 1 LAST PACK_TYPE PIP
J 0
(-400 5350);
PAINT SKYBLUE (-400 5350);
DISPLAY INVISIBLE (-400 5350);
FORCEPROP 2 LAST BOM_COST MEM
J 0
(0 4200);
PAINT ORANGE (0 4200);
DISPLAY INVISIBLE (0 4200);
FORCEPROP 2 LAST CDS_LIB mstr_sconn
J 0
(0 4200);
PAINT ORANGE (0 4200);
DISPLAY INVISIBLE (0 4200);
FORCEPROP 2 LAST SEC_TYPE PIP
J 0
(-400 5350);
DISPLAY 1.021277 (-400 5350);
PAINT ORANGE (-400 5350);
DISPLAY INVISIBLE (-400 5350);
FORCEPROP 2 LAST SEC 2
J 0
(-400 5350);
DISPLAY 0.680851 (-400 5350);
PAINT MONO (-400 5350);
DISPLAY INVISIBLE (-400 5350);
FORCEPROP 2 LAST CDS_LOCATION J1G1
J 0
(-400 5300);
DISPLAY 0.617021 (-400 5300);
PAINT AQUA (-400 5300);
DISPLAY INVISIBLE (-400 5300);
FORCEPROP 1 LAST PATH I66
J 0
(0 5250);
PAINT GREEN (0 5250);
DISPLAY INVISIBLE (0 5250);
FORCEPROP 2 LAST ROOM DDR4_CH_G
J 0
(0 4200);
PAINT ORANGE (0 4200);
DISPLAY INVISIBLE (0 4200);
FORCEADD TAP..6
R 2
(-1625 3325);
FORCEPROP 3 LASTPIN (-1675 3325) SIG_NAME M_G_DQ<40>
J 0
(-1665 3335);
DISPLAY 0.659574 (-1665 3335);
PAINT MONO (-1665 3335);
DISPLAY INVISIBLE (-1665 3335);
FORCEPROP 1 LASTPIN (-1675 3325) BN 40
J 2
(-1625 3335);
DISPLAY 0.617021 (-1625 3335);
PAINT PINK (-1625 3335);
FORCEPROP 2 LAST CDS_LIB mstr_standard
J 2
(-1625 3325);
DISPLAY 0.787234 (-1625 3325);
PAINT MONO (-1625 3325);
DISPLAY INVISIBLE (-1625 3325);
FORCEPROP 1 LAST BODY_TYPE PLUMBING
J 2
(-1625 3275);
DISPLAY 1.234043 (-1625 3275);
PAINT GREEN (-1625 3275);
DISPLAY INVISIBLE (-1625 3275);
FORCEPROP 1 LAST HDL_TAP TRUE
J 2
(-1950 3200);
DISPLAY 1.234043 (-1950 3200);
PAINT GREEN (-1950 3200);
DISPLAY INVISIBLE (-1950 3200);
FORCEPROP 1 LAST PATH I67
J 2
(-1625 3325);
DISPLAY 0.936170 (-1625 3325);
PAINT GREEN (-1625 3325);
DISPLAY INVISIBLE (-1625 3325);
FORCEADD TAP..6
R 2
(-1625 3375);
FORCEPROP 3 LASTPIN (-1675 3375) SIG_NAME M_G_DQ<43>
J 0
(-1665 3385);
DISPLAY 0.659574 (-1665 3385);
PAINT MONO (-1665 3385);
DISPLAY INVISIBLE (-1665 3385);
FORCEPROP 1 LASTPIN (-1675 3375) BN 43
J 2
(-1625 3385);
DISPLAY 0.617021 (-1625 3385);
PAINT PINK (-1625 3385);
FORCEPROP 2 LAST CDS_LIB mstr_standard
J 2
(-1625 3375);
DISPLAY 0.787234 (-1625 3375);
PAINT MONO (-1625 3375);
DISPLAY INVISIBLE (-1625 3375);
FORCEPROP 1 LAST BODY_TYPE PLUMBING
J 2
(-1625 3325);
DISPLAY 1.234043 (-1625 3325);
PAINT GREEN (-1625 3325);
DISPLAY INVISIBLE (-1625 3325);
FORCEPROP 1 LAST HDL_TAP TRUE
J 2
(-1950 3250);
DISPLAY 1.234043 (-1950 3250);
PAINT GREEN (-1950 3250);
DISPLAY INVISIBLE (-1950 3250);
FORCEPROP 1 LAST PATH I68
J 2
(-1625 3375);
DISPLAY 0.936170 (-1625 3375);
PAINT GREEN (-1625 3375);
DISPLAY INVISIBLE (-1625 3375);
FORCEADD TAP..6
R 2
(-1625 3425);
FORCEPROP 3 LASTPIN (-1675 3425) SIG_NAME M_G_DQ<42>
J 0
(-1665 3435);
DISPLAY 0.659574 (-1665 3435);
PAINT MONO (-1665 3435);
DISPLAY INVISIBLE (-1665 3435);
FORCEPROP 1 LASTPIN (-1675 3425) BN 42
J 2
(-1625 3435);
DISPLAY 0.617021 (-1625 3435);
PAINT PINK (-1625 3435);
FORCEPROP 2 LAST CDS_LIB mstr_standard
J 2
(-1625 3425);
DISPLAY 0.787234 (-1625 3425);
PAINT MONO (-1625 3425);
DISPLAY INVISIBLE (-1625 3425);
FORCEPROP 1 LAST BODY_TYPE PLUMBING
J 2
(-1625 3375);
DISPLAY 1.234043 (-1625 3375);
PAINT GREEN (-1625 3375);
DISPLAY INVISIBLE (-1625 3375);
FORCEPROP 1 LAST HDL_TAP TRUE
J 2
(-1950 3300);
DISPLAY 1.234043 (-1950 3300);
PAINT GREEN (-1950 3300);
DISPLAY INVISIBLE (-1950 3300);
FORCEPROP 1 LAST PATH I69
J 2
(-1625 3425);
DISPLAY 0.936170 (-1625 3425);
PAINT GREEN (-1625 3425);
DISPLAY INVISIBLE (-1625 3425);
FORCEADD TAP..6
R 2
(900 4600);
FORCEPROP 3 LASTPIN (850 4600) SIG_NAME M_G_DQS_DN<13>
J 0
(860 4610);
DISPLAY 0.659574 (860 4610);
PAINT MONO (860 4610);
DISPLAY INVISIBLE (860 4610);
FORCEPROP 1 LASTPIN (850 4600) BN 13
J 2
(900 4610);
DISPLAY 0.617021 (900 4610);
PAINT PINK (900 4610);
FORCEPROP 2 LAST CDS_LIB mstr_standard
J 0
(900 4600);
DISPLAY 0.787234 (900 4600);
PAINT MONO (900 4600);
DISPLAY INVISIBLE (900 4600);
FORCEPROP 1 LAST BODY_TYPE PLUMBING
J 2
(900 4550);
DISPLAY 1.234043 (900 4550);
PAINT GREEN (900 4550);
DISPLAY INVISIBLE (900 4550);
FORCEPROP 1 LAST HDL_TAP TRUE
J 2
(575 4475);
DISPLAY 1.234043 (575 4475);
PAINT GREEN (575 4475);
DISPLAY INVISIBLE (575 4475);
FORCEPROP 1 LAST PATH I7
J 2
(900 4600);
DISPLAY 0.936170 (900 4600);
PAINT GREEN (900 4600);
DISPLAY INVISIBLE (900 4600);
FORCEADD TAP..6
R 2
(-1625 3225);
FORCEPROP 3 LASTPIN (-1675 3225) SIG_NAME M_G_DQ<38>
J 0
(-1665 3235);
DISPLAY 0.659574 (-1665 3235);
PAINT MONO (-1665 3235);
DISPLAY INVISIBLE (-1665 3235);
FORCEPROP 1 LASTPIN (-1675 3225) BN 38
J 2
(-1625 3235);
DISPLAY 0.617021 (-1625 3235);
PAINT PINK (-1625 3235);
FORCEPROP 2 LAST CDS_LIB mstr_standard
J 2
(-1625 3225);
DISPLAY 0.787234 (-1625 3225);
PAINT MONO (-1625 3225);
DISPLAY INVISIBLE (-1625 3225);
FORCEPROP 1 LAST BODY_TYPE PLUMBING
J 2
(-1625 3175);
DISPLAY 1.234043 (-1625 3175);
PAINT GREEN (-1625 3175);
DISPLAY INVISIBLE (-1625 3175);
FORCEPROP 1 LAST HDL_TAP TRUE
J 2
(-1950 3100);
DISPLAY 1.234043 (-1950 3100);
PAINT GREEN (-1950 3100);
DISPLAY INVISIBLE (-1950 3100);
FORCEPROP 1 LAST PATH I70
J 2
(-1625 3225);
DISPLAY 0.936170 (-1625 3225);
PAINT GREEN (-1625 3225);
DISPLAY INVISIBLE (-1625 3225);
FORCEADD TAP..6
R 2
(-1625 3275);
FORCEPROP 3 LASTPIN (-1675 3275) SIG_NAME M_G_DQ<41>
J 0
(-1665 3285);
DISPLAY 0.659574 (-1665 3285);
PAINT MONO (-1665 3285);
DISPLAY INVISIBLE (-1665 3285);
FORCEPROP 1 LASTPIN (-1675 3275) BN 41
J 2
(-1625 3285);
DISPLAY 0.617021 (-1625 3285);
PAINT PINK (-1625 3285);
FORCEPROP 2 LAST CDS_LIB mstr_standard
J 2
(-1625 3275);
DISPLAY 0.787234 (-1625 3275);
PAINT MONO (-1625 3275);
DISPLAY INVISIBLE (-1625 3275);
FORCEPROP 1 LAST BODY_TYPE PLUMBING
J 2
(-1625 3225);
DISPLAY 1.234043 (-1625 3225);
PAINT GREEN (-1625 3225);
DISPLAY INVISIBLE (-1625 3225);
FORCEPROP 1 LAST HDL_TAP TRUE
J 2
(-1950 3150);
DISPLAY 1.234043 (-1950 3150);
PAINT GREEN (-1950 3150);
DISPLAY INVISIBLE (-1950 3150);
FORCEPROP 1 LAST PATH I71
J 2
(-1625 3275);
DISPLAY 0.936170 (-1625 3275);
PAINT GREEN (-1625 3275);
DISPLAY INVISIBLE (-1625 3275);
FORCEADD TAP..6
R 2
(-1625 3075);
FORCEPROP 3 LASTPIN (-1675 3075) SIG_NAME M_G_DQ<37>
J 0
(-1665 3085);
DISPLAY 0.659574 (-1665 3085);
PAINT MONO (-1665 3085);
DISPLAY INVISIBLE (-1665 3085);
FORCEPROP 1 LASTPIN (-1675 3075) BN 37
J 2
(-1625 3085);
DISPLAY 0.617021 (-1625 3085);
PAINT PINK (-1625 3085);
FORCEPROP 2 LAST CDS_LIB mstr_standard
J 2
(-1625 3075);
DISPLAY 0.787234 (-1625 3075);
PAINT MONO (-1625 3075);
DISPLAY INVISIBLE (-1625 3075);
FORCEPROP 1 LAST BODY_TYPE PLUMBING
J 2
(-1625 3025);
DISPLAY 1.234043 (-1625 3025);
PAINT GREEN (-1625 3025);
DISPLAY INVISIBLE (-1625 3025);
FORCEPROP 1 LAST HDL_TAP TRUE
J 2
(-1950 2950);
DISPLAY 1.234043 (-1950 2950);
PAINT GREEN (-1950 2950);
DISPLAY INVISIBLE (-1950 2950);
FORCEPROP 1 LAST PATH I72
J 2
(-1625 3075);
DISPLAY 0.936170 (-1625 3075);
PAINT GREEN (-1625 3075);
DISPLAY INVISIBLE (-1625 3075);
FORCEADD TAP..6
R 2
(-1625 3125);
FORCEPROP 3 LASTPIN (-1675 3125) SIG_NAME M_G_DQ<36>
J 0
(-1665 3135);
DISPLAY 0.659574 (-1665 3135);
PAINT MONO (-1665 3135);
DISPLAY INVISIBLE (-1665 3135);
FORCEPROP 1 LASTPIN (-1675 3125) BN 36
J 2
(-1625 3135);
DISPLAY 0.617021 (-1625 3135);
PAINT PINK (-1625 3135);
FORCEPROP 2 LAST CDS_LIB mstr_standard
J 2
(-1625 3125);
DISPLAY 0.787234 (-1625 3125);
PAINT MONO (-1625 3125);
DISPLAY INVISIBLE (-1625 3125);
FORCEPROP 1 LAST BODY_TYPE PLUMBING
J 2
(-1625 3075);
DISPLAY 1.234043 (-1625 3075);
PAINT GREEN (-1625 3075);
DISPLAY INVISIBLE (-1625 3075);
FORCEPROP 1 LAST HDL_TAP TRUE
J 2
(-1950 3000);
DISPLAY 1.234043 (-1950 3000);
PAINT GREEN (-1950 3000);
DISPLAY INVISIBLE (-1950 3000);
FORCEPROP 1 LAST PATH I73
J 2
(-1625 3125);
DISPLAY 0.936170 (-1625 3125);
PAINT GREEN (-1625 3125);
DISPLAY INVISIBLE (-1625 3125);
FORCEADD TAP..6
R 2
(-1625 3175);
FORCEPROP 3 LASTPIN (-1675 3175) SIG_NAME M_G_DQ<39>
J 0
(-1665 3185);
DISPLAY 0.659574 (-1665 3185);
PAINT MONO (-1665 3185);
DISPLAY INVISIBLE (-1665 3185);
FORCEPROP 1 LASTPIN (-1675 3175) BN 39
J 2
(-1625 3185);
DISPLAY 0.617021 (-1625 3185);
PAINT PINK (-1625 3185);
FORCEPROP 2 LAST CDS_LIB mstr_standard
J 2
(-1625 3175);
DISPLAY 0.787234 (-1625 3175);
PAINT MONO (-1625 3175);
DISPLAY INVISIBLE (-1625 3175);
FORCEPROP 1 LAST BODY_TYPE PLUMBING
J 2
(-1625 3125);
DISPLAY 1.234043 (-1625 3125);
PAINT GREEN (-1625 3125);
DISPLAY INVISIBLE (-1625 3125);
FORCEPROP 1 LAST HDL_TAP TRUE
J 2
(-1950 3050);
DISPLAY 1.234043 (-1950 3050);
PAINT GREEN (-1950 3050);
DISPLAY INVISIBLE (-1950 3050);
FORCEPROP 1 LAST PATH I74
J 2
(-1625 3175);
DISPLAY 0.936170 (-1625 3175);
PAINT GREEN (-1625 3175);
DISPLAY INVISIBLE (-1625 3175);
FORCEADD TAP..6
R 2
(-1625 2975);
FORCEPROP 3 LASTPIN (-1675 2975) SIG_NAME M_G_DQ<35>
J 0
(-1665 2985);
DISPLAY 0.659574 (-1665 2985);
PAINT MONO (-1665 2985);
DISPLAY INVISIBLE (-1665 2985);
FORCEPROP 1 LASTPIN (-1675 2975) BN 35
J 2
(-1625 2985);
DISPLAY 0.617021 (-1625 2985);
PAINT PINK (-1625 2985);
FORCEPROP 2 LAST CDS_LIB mstr_standard
J 2
(-1625 2975);
DISPLAY 0.787234 (-1625 2975);
PAINT MONO (-1625 2975);
DISPLAY INVISIBLE (-1625 2975);
FORCEPROP 1 LAST BODY_TYPE PLUMBING
J 2
(-1625 2925);
DISPLAY 1.234043 (-1625 2925);
PAINT GREEN (-1625 2925);
DISPLAY INVISIBLE (-1625 2925);
FORCEPROP 1 LAST HDL_TAP TRUE
J 2
(-1950 2850);
DISPLAY 1.234043 (-1950 2850);
PAINT GREEN (-1950 2850);
DISPLAY INVISIBLE (-1950 2850);
FORCEPROP 1 LAST PATH I75
J 2
(-1625 2975);
DISPLAY 0.936170 (-1625 2975);
PAINT GREEN (-1625 2975);
DISPLAY INVISIBLE (-1625 2975);
FORCEADD TAP..6
R 2
(-1625 3025);
FORCEPROP 3 LASTPIN (-1675 3025) SIG_NAME M_G_DQ<34>
J 0
(-1665 3035);
DISPLAY 0.659574 (-1665 3035);
PAINT MONO (-1665 3035);
DISPLAY INVISIBLE (-1665 3035);
FORCEPROP 1 LASTPIN (-1675 3025) BN 34
J 2
(-1625 3035);
DISPLAY 0.617021 (-1625 3035);
PAINT PINK (-1625 3035);
FORCEPROP 2 LAST CDS_LIB mstr_standard
J 2
(-1625 3025);
DISPLAY 0.787234 (-1625 3025);
PAINT MONO (-1625 3025);
DISPLAY INVISIBLE (-1625 3025);
FORCEPROP 1 LAST BODY_TYPE PLUMBING
J 2
(-1625 2975);
DISPLAY 1.234043 (-1625 2975);
PAINT GREEN (-1625 2975);
DISPLAY INVISIBLE (-1625 2975);
FORCEPROP 1 LAST HDL_TAP TRUE
J 2
(-1950 2900);
DISPLAY 1.234043 (-1950 2900);
PAINT GREEN (-1950 2900);
DISPLAY INVISIBLE (-1950 2900);
FORCEPROP 1 LAST PATH I76
J 2
(-1625 3025);
DISPLAY 0.936170 (-1625 3025);
PAINT GREEN (-1625 3025);
DISPLAY INVISIBLE (-1625 3025);
FORCEADD TAP..6
R 2
(-1625 2825);
FORCEPROP 3 LASTPIN (-1675 2825) SIG_NAME M_G_DQ<30>
J 0
(-1665 2835);
DISPLAY 0.659574 (-1665 2835);
PAINT MONO (-1665 2835);
DISPLAY INVISIBLE (-1665 2835);
FORCEPROP 1 LASTPIN (-1675 2825) BN 30
J 2
(-1625 2835);
DISPLAY 0.617021 (-1625 2835);
PAINT PINK (-1625 2835);
FORCEPROP 2 LAST CDS_LIB mstr_standard
J 2
(-1625 2825);
DISPLAY 0.787234 (-1625 2825);
PAINT MONO (-1625 2825);
DISPLAY INVISIBLE (-1625 2825);
FORCEPROP 1 LAST BODY_TYPE PLUMBING
J 2
(-1625 2775);
DISPLAY 1.234043 (-1625 2775);
PAINT GREEN (-1625 2775);
DISPLAY INVISIBLE (-1625 2775);
FORCEPROP 1 LAST HDL_TAP TRUE
J 2
(-1950 2700);
DISPLAY 1.234043 (-1950 2700);
PAINT GREEN (-1950 2700);
DISPLAY INVISIBLE (-1950 2700);
FORCEPROP 1 LAST PATH I77
J 2
(-1625 2825);
DISPLAY 0.936170 (-1625 2825);
PAINT GREEN (-1625 2825);
DISPLAY INVISIBLE (-1625 2825);
FORCEADD TAP..6
R 2
(-1625 2875);
FORCEPROP 3 LASTPIN (-1675 2875) SIG_NAME M_G_DQ<33>
J 0
(-1665 2885);
DISPLAY 0.659574 (-1665 2885);
PAINT MONO (-1665 2885);
DISPLAY INVISIBLE (-1665 2885);
FORCEPROP 1 LASTPIN (-1675 2875) BN 33
J 2
(-1625 2885);
DISPLAY 0.617021 (-1625 2885);
PAINT PINK (-1625 2885);
FORCEPROP 2 LAST CDS_LIB mstr_standard
J 2
(-1625 2875);
DISPLAY 0.787234 (-1625 2875);
PAINT MONO (-1625 2875);
DISPLAY INVISIBLE (-1625 2875);
FORCEPROP 1 LAST BODY_TYPE PLUMBING
J 2
(-1625 2825);
DISPLAY 1.234043 (-1625 2825);
PAINT GREEN (-1625 2825);
DISPLAY INVISIBLE (-1625 2825);
FORCEPROP 1 LAST HDL_TAP TRUE
J 2
(-1950 2750);
DISPLAY 1.234043 (-1950 2750);
PAINT GREEN (-1950 2750);
DISPLAY INVISIBLE (-1950 2750);
FORCEPROP 1 LAST PATH I78
J 2
(-1625 2875);
DISPLAY 0.936170 (-1625 2875);
PAINT GREEN (-1625 2875);
DISPLAY INVISIBLE (-1625 2875);
FORCEADD TAP..6
R 2
(-1625 2925);
FORCEPROP 3 LASTPIN (-1675 2925) SIG_NAME M_G_DQ<32>
J 0
(-1665 2935);
DISPLAY 0.659574 (-1665 2935);
PAINT MONO (-1665 2935);
DISPLAY INVISIBLE (-1665 2935);
FORCEPROP 1 LASTPIN (-1675 2925) BN 32
J 2
(-1625 2935);
DISPLAY 0.617021 (-1625 2935);
PAINT PINK (-1625 2935);
FORCEPROP 2 LAST CDS_LIB mstr_standard
J 2
(-1625 2925);
DISPLAY 0.787234 (-1625 2925);
PAINT MONO (-1625 2925);
DISPLAY INVISIBLE (-1625 2925);
FORCEPROP 1 LAST BODY_TYPE PLUMBING
J 2
(-1625 2875);
DISPLAY 1.234043 (-1625 2875);
PAINT GREEN (-1625 2875);
DISPLAY INVISIBLE (-1625 2875);
FORCEPROP 1 LAST HDL_TAP TRUE
J 2
(-1950 2800);
DISPLAY 1.234043 (-1950 2800);
PAINT GREEN (-1950 2800);
DISPLAY INVISIBLE (-1950 2800);
FORCEPROP 1 LAST PATH I79
J 2
(-1625 2925);
DISPLAY 0.936170 (-1625 2925);
PAINT GREEN (-1625 2925);
DISPLAY INVISIBLE (-1625 2925);
FORCEADD TAP..6
R 2
(900 4700);
FORCEPROP 3 LASTPIN (850 4700) SIG_NAME M_G_DQS_DN<14>
J 0
(860 4710);
DISPLAY 0.659574 (860 4710);
PAINT MONO (860 4710);
DISPLAY INVISIBLE (860 4710);
FORCEPROP 1 LASTPIN (850 4700) BN 14
J 2
(900 4710);
DISPLAY 0.617021 (900 4710);
PAINT PINK (900 4710);
FORCEPROP 2 LAST CDS_LIB mstr_standard
J 0
(900 4700);
DISPLAY 0.787234 (900 4700);
PAINT MONO (900 4700);
DISPLAY INVISIBLE (900 4700);
FORCEPROP 1 LAST BODY_TYPE PLUMBING
J 2
(900 4650);
DISPLAY 1.234043 (900 4650);
PAINT GREEN (900 4650);
DISPLAY INVISIBLE (900 4650);
FORCEPROP 1 LAST HDL_TAP TRUE
J 2
(575 4575);
DISPLAY 1.234043 (575 4575);
PAINT GREEN (575 4575);
DISPLAY INVISIBLE (575 4575);
FORCEPROP 1 LAST PATH I8
J 2
(900 4700);
DISPLAY 0.936170 (900 4700);
PAINT GREEN (900 4700);
DISPLAY INVISIBLE (900 4700);
FORCEADD TAP..6
R 2
(-1625 2775);
FORCEPROP 3 LASTPIN (-1675 2775) SIG_NAME M_G_DQ<31>
J 0
(-1665 2785);
DISPLAY 0.659574 (-1665 2785);
PAINT MONO (-1665 2785);
DISPLAY INVISIBLE (-1665 2785);
FORCEPROP 1 LASTPIN (-1675 2775) BN 31
J 2
(-1625 2785);
DISPLAY 0.617021 (-1625 2785);
PAINT PINK (-1625 2785);
FORCEPROP 2 LAST CDS_LIB mstr_standard
J 2
(-1625 2775);
DISPLAY 0.787234 (-1625 2775);
PAINT MONO (-1625 2775);
DISPLAY INVISIBLE (-1625 2775);
FORCEPROP 1 LAST BODY_TYPE PLUMBING
J 2
(-1625 2725);
DISPLAY 1.234043 (-1625 2725);
PAINT GREEN (-1625 2725);
DISPLAY INVISIBLE (-1625 2725);
FORCEPROP 1 LAST HDL_TAP TRUE
J 2
(-1950 2650);
DISPLAY 1.234043 (-1950 2650);
PAINT GREEN (-1950 2650);
DISPLAY INVISIBLE (-1950 2650);
FORCEPROP 1 LAST PATH I80
J 2
(-1625 2775);
DISPLAY 0.936170 (-1625 2775);
PAINT GREEN (-1625 2775);
DISPLAY INVISIBLE (-1625 2775);
FORCEADD TAP..6
R 2
(-1625 2725);
FORCEPROP 3 LASTPIN (-1675 2725) SIG_NAME M_G_DQ<28>
J 0
(-1665 2735);
DISPLAY 0.659574 (-1665 2735);
PAINT MONO (-1665 2735);
DISPLAY INVISIBLE (-1665 2735);
FORCEPROP 1 LASTPIN (-1675 2725) BN 28
J 2
(-1625 2735);
DISPLAY 0.617021 (-1625 2735);
PAINT PINK (-1625 2735);
FORCEPROP 2 LAST CDS_LIB mstr_standard
J 2
(-1625 2725);
DISPLAY 0.787234 (-1625 2725);
PAINT MONO (-1625 2725);
DISPLAY INVISIBLE (-1625 2725);
FORCEPROP 1 LAST BODY_TYPE PLUMBING
J 2
(-1625 2675);
DISPLAY 1.234043 (-1625 2675);
PAINT GREEN (-1625 2675);
DISPLAY INVISIBLE (-1625 2675);
FORCEPROP 1 LAST HDL_TAP TRUE
J 2
(-1950 2600);
DISPLAY 1.234043 (-1950 2600);
PAINT GREEN (-1950 2600);
DISPLAY INVISIBLE (-1950 2600);
FORCEPROP 1 LAST PATH I81
J 2
(-1625 2725);
DISPLAY 0.936170 (-1625 2725);
PAINT GREEN (-1625 2725);
DISPLAY INVISIBLE (-1625 2725);
FORCEADD TAP..6
R 2
(-1625 2575);
FORCEPROP 3 LASTPIN (-1675 2575) SIG_NAME M_G_DQ<27>
J 0
(-1665 2585);
DISPLAY 0.659574 (-1665 2585);
PAINT MONO (-1665 2585);
DISPLAY INVISIBLE (-1665 2585);
FORCEPROP 1 LASTPIN (-1675 2575) BN 27
J 2
(-1625 2585);
DISPLAY 0.617021 (-1625 2585);
PAINT PINK (-1625 2585);
FORCEPROP 2 LAST CDS_LIB mstr_standard
J 2
(-1625 2575);
DISPLAY 0.787234 (-1625 2575);
PAINT MONO (-1625 2575);
DISPLAY INVISIBLE (-1625 2575);
FORCEPROP 1 LAST BODY_TYPE PLUMBING
J 2
(-1625 2525);
DISPLAY 1.234043 (-1625 2525);
PAINT GREEN (-1625 2525);
DISPLAY INVISIBLE (-1625 2525);
FORCEPROP 1 LAST HDL_TAP TRUE
J 2
(-1950 2450);
DISPLAY 1.234043 (-1950 2450);
PAINT GREEN (-1950 2450);
DISPLAY INVISIBLE (-1950 2450);
FORCEPROP 1 LAST PATH I82
J 2
(-1625 2575);
DISPLAY 0.936170 (-1625 2575);
PAINT GREEN (-1625 2575);
DISPLAY INVISIBLE (-1625 2575);
FORCEADD TAP..6
R 2
(-1625 2675);
FORCEPROP 3 LASTPIN (-1675 2675) SIG_NAME M_G_DQ<29>
J 0
(-1665 2685);
DISPLAY 0.659574 (-1665 2685);
PAINT MONO (-1665 2685);
DISPLAY INVISIBLE (-1665 2685);
FORCEPROP 1 LASTPIN (-1675 2675) BN 29
J 2
(-1625 2685);
DISPLAY 0.617021 (-1625 2685);
PAINT PINK (-1625 2685);
FORCEPROP 2 LAST CDS_LIB mstr_standard
J 2
(-1625 2675);
DISPLAY 0.787234 (-1625 2675);
PAINT MONO (-1625 2675);
DISPLAY INVISIBLE (-1625 2675);
FORCEPROP 1 LAST BODY_TYPE PLUMBING
J 2
(-1625 2625);
DISPLAY 1.234043 (-1625 2625);
PAINT GREEN (-1625 2625);
DISPLAY INVISIBLE (-1625 2625);
FORCEPROP 1 LAST HDL_TAP TRUE
J 2
(-1950 2550);
DISPLAY 1.234043 (-1950 2550);
PAINT GREEN (-1950 2550);
DISPLAY INVISIBLE (-1950 2550);
FORCEPROP 1 LAST PATH I83
J 2
(-1625 2675);
DISPLAY 0.936170 (-1625 2675);
PAINT GREEN (-1625 2675);
DISPLAY INVISIBLE (-1625 2675);
FORCEADD TAP..6
R 2
(-1625 2625);
FORCEPROP 3 LASTPIN (-1675 2625) SIG_NAME M_G_DQ<26>
J 0
(-1665 2635);
DISPLAY 0.659574 (-1665 2635);
PAINT MONO (-1665 2635);
DISPLAY INVISIBLE (-1665 2635);
FORCEPROP 1 LASTPIN (-1675 2625) BN 26
J 2
(-1625 2635);
DISPLAY 0.617021 (-1625 2635);
PAINT PINK (-1625 2635);
FORCEPROP 2 LAST CDS_LIB mstr_standard
J 2
(-1625 2625);
DISPLAY 0.787234 (-1625 2625);
PAINT MONO (-1625 2625);
DISPLAY INVISIBLE (-1625 2625);
FORCEPROP 1 LAST BODY_TYPE PLUMBING
J 2
(-1625 2575);
DISPLAY 1.234043 (-1625 2575);
PAINT GREEN (-1625 2575);
DISPLAY INVISIBLE (-1625 2575);
FORCEPROP 1 LAST HDL_TAP TRUE
J 2
(-1950 2500);
DISPLAY 1.234043 (-1950 2500);
PAINT GREEN (-1950 2500);
DISPLAY INVISIBLE (-1950 2500);
FORCEPROP 1 LAST PATH I84
J 2
(-1625 2625);
DISPLAY 0.936170 (-1625 2625);
PAINT GREEN (-1625 2625);
DISPLAY INVISIBLE (-1625 2625);
FORCEADD TAP..6
R 2
(-1625 2475);
FORCEPROP 3 LASTPIN (-1675 2475) SIG_NAME M_G_DQ<25>
J 0
(-1665 2485);
DISPLAY 0.659574 (-1665 2485);
PAINT MONO (-1665 2485);
DISPLAY INVISIBLE (-1665 2485);
FORCEPROP 1 LASTPIN (-1675 2475) BN 25
J 2
(-1625 2485);
DISPLAY 0.617021 (-1625 2485);
PAINT PINK (-1625 2485);
FORCEPROP 2 LAST CDS_LIB mstr_standard
J 2
(-1625 2475);
DISPLAY 0.787234 (-1625 2475);
PAINT MONO (-1625 2475);
DISPLAY INVISIBLE (-1625 2475);
FORCEPROP 1 LAST BODY_TYPE PLUMBING
J 2
(-1625 2425);
DISPLAY 1.234043 (-1625 2425);
PAINT GREEN (-1625 2425);
DISPLAY INVISIBLE (-1625 2425);
FORCEPROP 1 LAST HDL_TAP TRUE
J 2
(-1950 2350);
DISPLAY 1.234043 (-1950 2350);
PAINT GREEN (-1950 2350);
DISPLAY INVISIBLE (-1950 2350);
FORCEPROP 1 LAST PATH I85
J 2
(-1625 2475);
DISPLAY 0.936170 (-1625 2475);
PAINT GREEN (-1625 2475);
DISPLAY INVISIBLE (-1625 2475);
FORCEADD TAP..6
R 2
(-1625 2525);
FORCEPROP 3 LASTPIN (-1675 2525) SIG_NAME M_G_DQ<24>
J 0
(-1665 2535);
DISPLAY 0.659574 (-1665 2535);
PAINT MONO (-1665 2535);
DISPLAY INVISIBLE (-1665 2535);
FORCEPROP 1 LASTPIN (-1675 2525) BN 24
J 2
(-1625 2535);
DISPLAY 0.617021 (-1625 2535);
PAINT PINK (-1625 2535);
FORCEPROP 2 LAST CDS_LIB mstr_standard
J 2
(-1625 2525);
DISPLAY 0.787234 (-1625 2525);
PAINT MONO (-1625 2525);
DISPLAY INVISIBLE (-1625 2525);
FORCEPROP 1 LAST BODY_TYPE PLUMBING
J 2
(-1625 2475);
DISPLAY 1.234043 (-1625 2475);
PAINT GREEN (-1625 2475);
DISPLAY INVISIBLE (-1625 2475);
FORCEPROP 1 LAST HDL_TAP TRUE
J 2
(-1950 2400);
DISPLAY 1.234043 (-1950 2400);
PAINT GREEN (-1950 2400);
DISPLAY INVISIBLE (-1950 2400);
FORCEPROP 1 LAST PATH I86
J 2
(-1625 2525);
DISPLAY 0.936170 (-1625 2525);
PAINT GREEN (-1625 2525);
DISPLAY INVISIBLE (-1625 2525);
FORCEADD TAP..6
R 2
(-1625 2325);
FORCEPROP 3 LASTPIN (-1675 2325) SIG_NAME M_G_DQ<20>
J 0
(-1665 2335);
DISPLAY 0.659574 (-1665 2335);
PAINT MONO (-1665 2335);
DISPLAY INVISIBLE (-1665 2335);
FORCEPROP 1 LASTPIN (-1675 2325) BN 20
J 2
(-1625 2335);
DISPLAY 0.617021 (-1625 2335);
PAINT PINK (-1625 2335);
FORCEPROP 2 LAST CDS_LIB mstr_standard
J 2
(-1625 2325);
DISPLAY 0.787234 (-1625 2325);
PAINT MONO (-1625 2325);
DISPLAY INVISIBLE (-1625 2325);
FORCEPROP 1 LAST BODY_TYPE PLUMBING
J 2
(-1625 2275);
DISPLAY 1.234043 (-1625 2275);
PAINT GREEN (-1625 2275);
DISPLAY INVISIBLE (-1625 2275);
FORCEPROP 1 LAST HDL_TAP TRUE
J 2
(-1950 2200);
DISPLAY 1.234043 (-1950 2200);
PAINT GREEN (-1950 2200);
DISPLAY INVISIBLE (-1950 2200);
FORCEPROP 1 LAST PATH I87
J 2
(-1625 2325);
DISPLAY 0.936170 (-1625 2325);
PAINT GREEN (-1625 2325);
DISPLAY INVISIBLE (-1625 2325);
FORCEADD TAP..6
R 2
(-1625 2425);
FORCEPROP 3 LASTPIN (-1675 2425) SIG_NAME M_G_DQ<22>
J 0
(-1665 2435);
DISPLAY 0.659574 (-1665 2435);
PAINT MONO (-1665 2435);
DISPLAY INVISIBLE (-1665 2435);
FORCEPROP 1 LASTPIN (-1675 2425) BN 22
J 2
(-1625 2435);
DISPLAY 0.617021 (-1625 2435);
PAINT PINK (-1625 2435);
FORCEPROP 2 LAST CDS_LIB mstr_standard
J 2
(-1625 2425);
DISPLAY 0.787234 (-1625 2425);
PAINT MONO (-1625 2425);
DISPLAY INVISIBLE (-1625 2425);
FORCEPROP 1 LAST BODY_TYPE PLUMBING
J 2
(-1625 2375);
DISPLAY 1.234043 (-1625 2375);
PAINT GREEN (-1625 2375);
DISPLAY INVISIBLE (-1625 2375);
FORCEPROP 1 LAST HDL_TAP TRUE
J 2
(-1950 2300);
DISPLAY 1.234043 (-1950 2300);
PAINT GREEN (-1950 2300);
DISPLAY INVISIBLE (-1950 2300);
FORCEPROP 1 LAST PATH I88
J 2
(-1625 2425);
DISPLAY 0.936170 (-1625 2425);
PAINT GREEN (-1625 2425);
DISPLAY INVISIBLE (-1625 2425);
FORCEADD TAP..6
R 2
(-1625 2375);
FORCEPROP 3 LASTPIN (-1675 2375) SIG_NAME M_G_DQ<23>
J 0
(-1665 2385);
DISPLAY 0.659574 (-1665 2385);
PAINT MONO (-1665 2385);
DISPLAY INVISIBLE (-1665 2385);
FORCEPROP 1 LASTPIN (-1675 2375) BN 23
J 2
(-1625 2385);
DISPLAY 0.617021 (-1625 2385);
PAINT PINK (-1625 2385);
FORCEPROP 2 LAST CDS_LIB mstr_standard
J 2
(-1625 2375);
DISPLAY 0.787234 (-1625 2375);
PAINT MONO (-1625 2375);
DISPLAY INVISIBLE (-1625 2375);
FORCEPROP 1 LAST BODY_TYPE PLUMBING
J 2
(-1625 2325);
DISPLAY 1.234043 (-1625 2325);
PAINT GREEN (-1625 2325);
DISPLAY INVISIBLE (-1625 2325);
FORCEPROP 1 LAST HDL_TAP TRUE
J 2
(-1950 2250);
DISPLAY 1.234043 (-1950 2250);
PAINT GREEN (-1950 2250);
DISPLAY INVISIBLE (-1950 2250);
FORCEPROP 1 LAST PATH I89
J 2
(-1625 2375);
DISPLAY 0.936170 (-1625 2375);
PAINT GREEN (-1625 2375);
DISPLAY INVISIBLE (-1625 2375);
FORCEADD TAP..6
R 2
(900 4500);
FORCEPROP 3 LASTPIN (850 4500) SIG_NAME M_G_DQS_DN<12>
J 0
(860 4510);
DISPLAY 0.659574 (860 4510);
PAINT MONO (860 4510);
DISPLAY INVISIBLE (860 4510);
FORCEPROP 1 LASTPIN (850 4500) BN 12
J 2
(900 4510);
DISPLAY 0.617021 (900 4510);
PAINT PINK (900 4510);
FORCEPROP 2 LAST CDS_LIB mstr_standard
J 0
(900 4500);
DISPLAY 0.787234 (900 4500);
PAINT MONO (900 4500);
DISPLAY INVISIBLE (900 4500);
FORCEPROP 1 LAST BODY_TYPE PLUMBING
J 2
(900 4450);
DISPLAY 1.234043 (900 4450);
PAINT GREEN (900 4450);
DISPLAY INVISIBLE (900 4450);
FORCEPROP 1 LAST HDL_TAP TRUE
J 2
(575 4375);
DISPLAY 1.234043 (575 4375);
PAINT GREEN (575 4375);
DISPLAY INVISIBLE (575 4375);
FORCEPROP 1 LAST PATH I9
J 2
(900 4500);
DISPLAY 0.936170 (900 4500);
PAINT GREEN (900 4500);
DISPLAY INVISIBLE (900 4500);
FORCEADD TAP..6
R 2
(-1625 2275);
FORCEPROP 3 LASTPIN (-1675 2275) SIG_NAME M_G_DQ<21>
J 0
(-1665 2285);
DISPLAY 0.659574 (-1665 2285);
PAINT MONO (-1665 2285);
DISPLAY INVISIBLE (-1665 2285);
FORCEPROP 1 LASTPIN (-1675 2275) BN 21
J 2
(-1625 2285);
DISPLAY 0.617021 (-1625 2285);
PAINT PINK (-1625 2285);
FORCEPROP 2 LAST CDS_LIB mstr_standard
J 2
(-1625 2275);
DISPLAY 0.787234 (-1625 2275);
PAINT MONO (-1625 2275);
DISPLAY INVISIBLE (-1625 2275);
FORCEPROP 1 LAST BODY_TYPE PLUMBING
J 2
(-1625 2225);
DISPLAY 1.234043 (-1625 2225);
PAINT GREEN (-1625 2225);
DISPLAY INVISIBLE (-1625 2225);
FORCEPROP 1 LAST HDL_TAP TRUE
J 2
(-1950 2150);
DISPLAY 1.234043 (-1950 2150);
PAINT GREEN (-1950 2150);
DISPLAY INVISIBLE (-1950 2150);
FORCEPROP 1 LAST PATH I90
J 2
(-1625 2275);
DISPLAY 0.936170 (-1625 2275);
PAINT GREEN (-1625 2275);
DISPLAY INVISIBLE (-1625 2275);
FORCEADD TAP..6
R 2
(-1625 2225);
FORCEPROP 3 LASTPIN (-1675 2225) SIG_NAME M_G_DQ<18>
J 0
(-1665 2235);
DISPLAY 0.659574 (-1665 2235);
PAINT MONO (-1665 2235);
DISPLAY INVISIBLE (-1665 2235);
FORCEPROP 1 LASTPIN (-1675 2225) BN 18
J 2
(-1625 2235);
DISPLAY 0.617021 (-1625 2235);
PAINT PINK (-1625 2235);
FORCEPROP 2 LAST CDS_LIB mstr_standard
J 2
(-1625 2225);
DISPLAY 0.787234 (-1625 2225);
PAINT MONO (-1625 2225);
DISPLAY INVISIBLE (-1625 2225);
FORCEPROP 1 LAST BODY_TYPE PLUMBING
J 2
(-1625 2175);
DISPLAY 1.234043 (-1625 2175);
PAINT GREEN (-1625 2175);
DISPLAY INVISIBLE (-1625 2175);
FORCEPROP 1 LAST HDL_TAP TRUE
J 2
(-1950 2100);
DISPLAY 1.234043 (-1950 2100);
PAINT GREEN (-1950 2100);
DISPLAY INVISIBLE (-1950 2100);
FORCEPROP 1 LAST PATH I91
J 2
(-1625 2225);
DISPLAY 0.936170 (-1625 2225);
PAINT GREEN (-1625 2225);
DISPLAY INVISIBLE (-1625 2225);
FORCEADD TAP..6
R 2
(-1625 2175);
FORCEPROP 3 LASTPIN (-1675 2175) SIG_NAME M_G_DQ<19>
J 0
(-1665 2185);
DISPLAY 0.659574 (-1665 2185);
PAINT MONO (-1665 2185);
DISPLAY INVISIBLE (-1665 2185);
FORCEPROP 1 LASTPIN (-1675 2175) BN 19
J 2
(-1625 2185);
DISPLAY 0.617021 (-1625 2185);
PAINT PINK (-1625 2185);
FORCEPROP 2 LAST CDS_LIB mstr_standard
J 2
(-1625 2175);
DISPLAY 0.787234 (-1625 2175);
PAINT MONO (-1625 2175);
DISPLAY INVISIBLE (-1625 2175);
FORCEPROP 1 LAST BODY_TYPE PLUMBING
J 2
(-1625 2125);
DISPLAY 1.234043 (-1625 2125);
PAINT GREEN (-1625 2125);
DISPLAY INVISIBLE (-1625 2125);
FORCEPROP 1 LAST HDL_TAP TRUE
J 2
(-1950 2050);
DISPLAY 1.234043 (-1950 2050);
PAINT GREEN (-1950 2050);
DISPLAY INVISIBLE (-1950 2050);
FORCEPROP 1 LAST PATH I92
J 2
(-1625 2175);
DISPLAY 0.936170 (-1625 2175);
PAINT GREEN (-1625 2175);
DISPLAY INVISIBLE (-1625 2175);
FORCEADD TAP..6
R 2
(-1625 2125);
FORCEPROP 3 LASTPIN (-1675 2125) SIG_NAME M_G_DQ<16>
J 0
(-1665 2135);
DISPLAY 0.659574 (-1665 2135);
PAINT MONO (-1665 2135);
DISPLAY INVISIBLE (-1665 2135);
FORCEPROP 1 LASTPIN (-1675 2125) BN 16
J 2
(-1625 2135);
DISPLAY 0.617021 (-1625 2135);
PAINT PINK (-1625 2135);
FORCEPROP 2 LAST CDS_LIB mstr_standard
J 2
(-1625 2125);
DISPLAY 0.787234 (-1625 2125);
PAINT MONO (-1625 2125);
DISPLAY INVISIBLE (-1625 2125);
FORCEPROP 1 LAST BODY_TYPE PLUMBING
J 2
(-1625 2075);
DISPLAY 1.234043 (-1625 2075);
PAINT GREEN (-1625 2075);
DISPLAY INVISIBLE (-1625 2075);
FORCEPROP 1 LAST HDL_TAP TRUE
J 2
(-1950 2000);
DISPLAY 1.234043 (-1950 2000);
PAINT GREEN (-1950 2000);
DISPLAY INVISIBLE (-1950 2000);
FORCEPROP 1 LAST PATH I93
J 2
(-1625 2125);
DISPLAY 0.936170 (-1625 2125);
PAINT GREEN (-1625 2125);
DISPLAY INVISIBLE (-1625 2125);
FORCEADD TAP..6
R 2
(-1625 2075);
FORCEPROP 3 LASTPIN (-1675 2075) SIG_NAME M_G_DQ<17>
J 0
(-1665 2085);
DISPLAY 0.659574 (-1665 2085);
PAINT MONO (-1665 2085);
DISPLAY INVISIBLE (-1665 2085);
FORCEPROP 1 LASTPIN (-1675 2075) BN 17
J 2
(-1625 2085);
DISPLAY 0.617021 (-1625 2085);
PAINT PINK (-1625 2085);
FORCEPROP 2 LAST CDS_LIB mstr_standard
J 2
(-1625 2075);
DISPLAY 0.787234 (-1625 2075);
PAINT MONO (-1625 2075);
DISPLAY INVISIBLE (-1625 2075);
FORCEPROP 1 LAST BODY_TYPE PLUMBING
J 2
(-1625 2025);
DISPLAY 1.234043 (-1625 2025);
PAINT GREEN (-1625 2025);
DISPLAY INVISIBLE (-1625 2025);
FORCEPROP 1 LAST HDL_TAP TRUE
J 2
(-1950 1950);
DISPLAY 1.234043 (-1950 1950);
PAINT GREEN (-1950 1950);
DISPLAY INVISIBLE (-1950 1950);
FORCEPROP 1 LAST PATH I94
J 2
(-1625 2075);
DISPLAY 0.936170 (-1625 2075);
PAINT GREEN (-1625 2075);
DISPLAY INVISIBLE (-1625 2075);
FORCEADD TAP..6
R 2
(-1625 2025);
FORCEPROP 3 LASTPIN (-1675 2025) SIG_NAME M_G_DQ<14>
J 0
(-1665 2035);
DISPLAY 0.659574 (-1665 2035);
PAINT MONO (-1665 2035);
DISPLAY INVISIBLE (-1665 2035);
FORCEPROP 1 LASTPIN (-1675 2025) BN 14
J 2
(-1625 2035);
DISPLAY 0.617021 (-1625 2035);
PAINT PINK (-1625 2035);
FORCEPROP 2 LAST CDS_LIB mstr_standard
J 2
(-1625 2025);
DISPLAY 0.787234 (-1625 2025);
PAINT MONO (-1625 2025);
DISPLAY INVISIBLE (-1625 2025);
FORCEPROP 1 LAST BODY_TYPE PLUMBING
J 2
(-1625 1975);
DISPLAY 1.234043 (-1625 1975);
PAINT GREEN (-1625 1975);
DISPLAY INVISIBLE (-1625 1975);
FORCEPROP 1 LAST HDL_TAP TRUE
J 2
(-1950 1900);
DISPLAY 1.234043 (-1950 1900);
PAINT GREEN (-1950 1900);
DISPLAY INVISIBLE (-1950 1900);
FORCEPROP 1 LAST PATH I95
J 2
(-1625 2025);
DISPLAY 0.936170 (-1625 2025);
PAINT GREEN (-1625 2025);
DISPLAY INVISIBLE (-1625 2025);
FORCEADD TAP..6
R 2
(-1625 1975);
FORCEPROP 3 LASTPIN (-1675 1975) SIG_NAME M_G_DQ<15>
J 0
(-1665 1985);
DISPLAY 0.659574 (-1665 1985);
PAINT MONO (-1665 1985);
DISPLAY INVISIBLE (-1665 1985);
FORCEPROP 1 LASTPIN (-1675 1975) BN 15
J 2
(-1625 1985);
DISPLAY 0.617021 (-1625 1985);
PAINT PINK (-1625 1985);
FORCEPROP 2 LAST CDS_LIB mstr_standard
J 2
(-1625 1975);
DISPLAY 0.787234 (-1625 1975);
PAINT MONO (-1625 1975);
DISPLAY INVISIBLE (-1625 1975);
FORCEPROP 1 LAST BODY_TYPE PLUMBING
J 2
(-1625 1925);
DISPLAY 1.234043 (-1625 1925);
PAINT GREEN (-1625 1925);
DISPLAY INVISIBLE (-1625 1925);
FORCEPROP 1 LAST HDL_TAP TRUE
J 2
(-1950 1850);
DISPLAY 1.234043 (-1950 1850);
PAINT GREEN (-1950 1850);
DISPLAY INVISIBLE (-1950 1850);
FORCEPROP 1 LAST PATH I96
J 2
(-1625 1975);
DISPLAY 0.936170 (-1625 1975);
PAINT GREEN (-1625 1975);
DISPLAY INVISIBLE (-1625 1975);
FORCEADD TAP..6
R 2
(-1625 1875);
FORCEPROP 3 LASTPIN (-1675 1875) SIG_NAME M_G_DQ<13>
J 0
(-1665 1885);
DISPLAY 0.659574 (-1665 1885);
PAINT MONO (-1665 1885);
DISPLAY INVISIBLE (-1665 1885);
FORCEPROP 1 LASTPIN (-1675 1875) BN 13
J 2
(-1625 1885);
DISPLAY 0.617021 (-1625 1885);
PAINT PINK (-1625 1885);
FORCEPROP 2 LAST CDS_LIB mstr_standard
J 2
(-1625 1875);
DISPLAY 0.787234 (-1625 1875);
PAINT MONO (-1625 1875);
DISPLAY INVISIBLE (-1625 1875);
FORCEPROP 1 LAST BODY_TYPE PLUMBING
J 2
(-1625 1825);
DISPLAY 1.234043 (-1625 1825);
PAINT GREEN (-1625 1825);
DISPLAY INVISIBLE (-1625 1825);
FORCEPROP 1 LAST HDL_TAP TRUE
J 2
(-1950 1750);
DISPLAY 1.234043 (-1950 1750);
PAINT GREEN (-1950 1750);
DISPLAY INVISIBLE (-1950 1750);
FORCEPROP 1 LAST PATH I97
J 2
(-1625 1875);
DISPLAY 0.936170 (-1625 1875);
PAINT GREEN (-1625 1875);
DISPLAY INVISIBLE (-1625 1875);
FORCEADD TAP..6
R 2
(-1625 1925);
FORCEPROP 3 LASTPIN (-1675 1925) SIG_NAME M_G_DQ<12>
J 0
(-1665 1935);
DISPLAY 0.659574 (-1665 1935);
PAINT MONO (-1665 1935);
DISPLAY INVISIBLE (-1665 1935);
FORCEPROP 1 LASTPIN (-1675 1925) BN 12
J 2
(-1625 1935);
DISPLAY 0.617021 (-1625 1935);
PAINT PINK (-1625 1935);
FORCEPROP 2 LAST CDS_LIB mstr_standard
J 2
(-1625 1925);
DISPLAY 0.787234 (-1625 1925);
PAINT MONO (-1625 1925);
DISPLAY INVISIBLE (-1625 1925);
FORCEPROP 1 LAST BODY_TYPE PLUMBING
J 2
(-1625 1875);
DISPLAY 1.234043 (-1625 1875);
PAINT GREEN (-1625 1875);
DISPLAY INVISIBLE (-1625 1875);
FORCEPROP 1 LAST HDL_TAP TRUE
J 2
(-1950 1800);
DISPLAY 1.234043 (-1950 1800);
PAINT GREEN (-1950 1800);
DISPLAY INVISIBLE (-1950 1800);
FORCEPROP 1 LAST PATH I98
J 2
(-1625 1925);
DISPLAY 0.936170 (-1625 1925);
PAINT GREEN (-1625 1925);
DISPLAY INVISIBLE (-1625 1925);
FORCEADD TAP..6
R 2
(-1625 1825);
FORCEPROP 3 LASTPIN (-1675 1825) SIG_NAME M_G_DQ<10>
J 0
(-1665 1835);
DISPLAY 0.659574 (-1665 1835);
PAINT MONO (-1665 1835);
DISPLAY INVISIBLE (-1665 1835);
FORCEPROP 1 LASTPIN (-1675 1825) BN 10
J 2
(-1625 1835);
DISPLAY 0.617021 (-1625 1835);
PAINT PINK (-1625 1835);
FORCEPROP 2 LAST CDS_LIB mstr_standard
J 2
(-1625 1825);
DISPLAY 0.787234 (-1625 1825);
PAINT MONO (-1625 1825);
DISPLAY INVISIBLE (-1625 1825);
FORCEPROP 1 LAST BODY_TYPE PLUMBING
J 2
(-1625 1775);
DISPLAY 1.234043 (-1625 1775);
PAINT GREEN (-1625 1775);
DISPLAY INVISIBLE (-1625 1775);
FORCEPROP 1 LAST HDL_TAP TRUE
J 2
(-1950 1700);
DISPLAY 1.234043 (-1950 1700);
PAINT GREEN (-1950 1700);
DISPLAY INVISIBLE (-1950 1700);
FORCEPROP 1 LAST PATH I99
J 2
(-1625 1825);
DISPLAY 0.936170 (-1625 1825);
PAINT GREEN (-1625 1825);
DISPLAY INVISIBLE (-1625 1825);
FORCEADD INTEL_CORP_BPAGE..1
(2650 375);
FORCEPROP 1 LAST CDS_CON_LAST_MODIFIED Fri Jun 16 17:48:28 2017
J 0
(1225 700);
DISPLAY 0.787234 (1225 700);
PAINT ORANGE (1225 700);
DISPLAY INVISIBLE (1225 700);
FORCEPROP 1 LAST CUSTOM_TXT_CDS <CURRENT_DESIGN_SHEET> OF <TOTAL_DESIGN_SHEETS>
J 0
(2150 400);
PAINT ORANGE (2150 400);
FORCEPROP 2 LAST CUSTOM_TXT_CDS <XR_PAGE_TITLE>
J 0
(-5240 5625);
DISPLAY 0.638298 (-5240 5625);
PAINT PINK (-5240 5625);
DISPLAY INVISIBLE (-5240 5625);
FORCEPROP 2 LAST CUSTOM_TXT_CDS <CON_LAST_MODIFIED>
J 0
(-1350 475);
DISPLAY 0.851064 (-1350 475);
PAINT ORANGE (-1350 475);
FORCEPROP 1 LAST SCH_TITLE CPU1 DDR4 CH G DIMM0
J 0
(-5300 425);
DISPLAY 1.212766 (-5300 425);
PAINT WHITE (-5300 425);
FORCEPROP 2 LAST CDS_LIB mstr_symbols
J 0
(2650 375);
DISPLAY 0.787234 (2650 375);
PAINT MONO (2650 375);
DISPLAY INVISIBLE (2650 375);
FORCEPROP 2 LAST PAGE_BORDER TRUE
J 0
(-5240 5625);
DISPLAY 0.680851 (-5240 5625);
PAINT PINK (-5240 5625);
DISPLAY INVISIBLE (-5240 5625);
FORCEPROP 1 LAST COMMENT_BODY TRUE
J 0
(2660 385);
DISPLAY 0.382979 (2660 385);
PAINT GREEN (2660 385);
DISPLAY INVISIBLE (2660 385);
FORCEPROP 2 LAST CDS_XR_PAGE_TITLE CR-77 : @BASEBOARD_FAB2_LIB.BASEBOARD_FAB2(SCH_1):PAGE77
J 0
(-5240 5625);
DISPLAY 0.638298 (-5240 5625);
PAINT PINK (-5240 5625);
DISPLAY INVISIBLE (-5240 5625);
FORCEADD BOM_NOTE..1
(-5050 5125);
FORCEPROP 0 LAST L1 STUFF FOR SKU A & B
J 0
(-5200 5025);
DISPLAY 1.063830 (-5200 5025);
PAINT WHITE (-5200 5025);
FORCEPROP 2 LAST CDS_LIB mstr_symbols
J 0
(-5050 5125);
PAINT ORANGE (-5050 5125);
DISPLAY INVISIBLE (-5050 5125);
FORCEPROP 2 LAST BOM_COST SB
J 0
(-5200 5100);
DISPLAY 1.361702 (-5200 5100);
PAINT ORANGE (-5200 5100);
DISPLAY INVISIBLE (-5200 5100);
FORCEPROP 1 LAST COMMENT_BODY TRUE
J 0
(-5025 5225);
DISPLAY 1.319149 (-5025 5225);
PAINT ORANGE (-5025 5225);
DISPLAY INVISIBLE (-5025 5225);
FORCEPROP 2 LAST ROOM SB_HEADERS
J 0
(-5200 5100);
DISPLAY 1.361702 (-5200 5100);
PAINT ORANGE (-5200 5100);
DISPLAY INVISIBLE (-5200 5100);
WIRE 16 -1 (-1350 2450)(-1350 2350);
WIRE 16 -1 (-1350 2350)(-1000 2350);
WIRE 16 -1 (-1000 2300)(-1000 2350);
WIRE 16 -1 (-1000 2350)(-800 2350);
WIRE 16 -1 (-1000 2250)(-1000 2300);
WIRE 16 -1 (-1000 2300)(-800 2300);
WIRE 16 -1 (-1000 2200)(-1000 2250);
WIRE 16 -1 (-1000 2250)(-800 2250);
WIRE 16 -1 (-1000 2150)(-1000 2200);
WIRE 16 -1 (-1000 2200)(-800 2200);
WIRE 16 -1 (-1000 2100)(-1000 2150);
WIRE 16 -1 (-1000 2150)(-800 2150);
WIRE 16 -1 (-1000 2050)(-1000 2100);
WIRE 16 -1 (-1000 2100)(-800 2100);
WIRE 16 -1 (-1000 2000)(-1000 2050);
WIRE 16 -1 (-1000 2050)(-800 2050);
WIRE 16 -1 (-1000 1950)(-1000 2000);
WIRE 16 -1 (-1000 2000)(-800 2000);
WIRE 16 -1 (-1000 1900)(-1000 1950);
WIRE 16 -1 (-1000 1950)(-800 1950);
WIRE 16 -1 (-1000 1850)(-1000 1900);
WIRE 16 -1 (-1000 1900)(-800 1900);
WIRE 16 -1 (-1000 1800)(-1000 1850);
WIRE 16 -1 (-1000 1850)(-800 1850);
WIRE 16 -1 (-1000 1750)(-1000 1800);
WIRE 16 -1 (-1000 1800)(-800 1800);
WIRE 16 -1 (-1000 1700)(-1000 1750);
WIRE 16 -1 (-1000 1750)(-800 1750);
WIRE 16 -1 (-1000 1650)(-1000 1700);
WIRE 16 -1 (-1000 1700)(-800 1700);
WIRE 16 -1 (-1000 1600)(-1000 1650);
WIRE 16 -1 (-1000 1650)(-800 1650);
WIRE 16 -1 (-1000 1550)(-1000 1600);
WIRE 16 -1 (-1000 1600)(-800 1600);
WIRE 16 -1 (-1000 1500)(-1000 1550);
WIRE 16 -1 (-1000 1550)(-800 1550);
WIRE 16 -1 (-1000 1450)(-1000 1500);
WIRE 16 -1 (-1000 1500)(-800 1500);
WIRE 16 -1 (-1000 1400)(-1000 1450);
WIRE 16 -1 (-1000 1450)(-800 1450);
WIRE 16 -1 (-1000 1350)(-1000 1400);
WIRE 16 -1 (-1000 1400)(-800 1400);
WIRE 16 -1 (-1000 1300)(-1000 1350);
WIRE 16 -1 (-1000 1350)(-800 1350);
WIRE 16 -1 (-1000 1250)(-1000 1300);
WIRE 16 -1 (-1000 1300)(-800 1300);
WIRE 16 -1 (-1000 1200)(-1000 1250);
WIRE 16 -1 (-1000 1250)(-800 1250);
WIRE 16 -1 (-1000 1150)(-1000 1200);
WIRE 16 -1 (-1000 1200)(-800 1200);
WIRE 16 -1 (-1000 1100)(-1000 1150);
WIRE 16 -1 (-1000 1150)(-800 1150);
WIRE 16 -1 (-1000 1100)(-800 1100);
WIRE 16 -1 (-1150 2600)(-1150 2500);
WIRE 16 -1 (-1150 2500)(-1000 2500);
WIRE 16 -1 (-1000 2450)(-1000 2500);
WIRE 16 -1 (-1000 2500)(-800 2500);
WIRE 16 -1 (-1000 2450)(-800 2450);
WIRE 16 -1 (2500 950)(2500 1050);
WIRE 16 -1 (2500 1050)(2500 1100);
WIRE 16 -1 (2500 1050)(2300 1050);
WIRE 16 -1 (2500 1100)(2500 1150);
WIRE 16 -1 (2500 1100)(2300 1100);
WIRE 16 -1 (2500 1150)(2500 1200);
WIRE 16 -1 (2500 1150)(2300 1150);
WIRE 16 -1 (2500 1200)(2500 1250);
WIRE 16 -1 (2500 1200)(2300 1200);
WIRE 16 -1 (2500 1250)(2500 1300);
WIRE 16 -1 (2500 1250)(2300 1250);
WIRE 16 -1 (2500 1300)(2500 1350);
WIRE 16 -1 (2500 1300)(2300 1300);
WIRE 16 -1 (2500 1350)(2500 1400);
WIRE 16 -1 (2500 1350)(2300 1350);
WIRE 16 -1 (2500 1400)(2500 1450);
WIRE 16 -1 (2500 1400)(2300 1400);
WIRE 16 -1 (2500 1450)(2500 1500);
WIRE 16 -1 (2500 1450)(2300 1450);
WIRE 16 -1 (2500 1500)(2500 1550);
WIRE 16 -1 (2500 1500)(2300 1500);
WIRE 16 -1 (2500 1550)(2500 1600);
WIRE 16 -1 (2500 1550)(2300 1550);
WIRE 16 -1 (2500 1600)(2500 1650);
WIRE 16 -1 (2500 1600)(2300 1600);
WIRE 16 -1 (2500 1650)(2500 1700);
WIRE 16 -1 (2500 1650)(2300 1650);
WIRE 16 -1 (2500 1700)(2500 1750);
WIRE 16 -1 (2500 1700)(2300 1700);
WIRE 16 -1 (2500 1750)(2500 1800);
WIRE 16 -1 (2500 1750)(2300 1750);
WIRE 16 -1 (2500 1800)(2500 1850);
WIRE 16 -1 (2500 1800)(2300 1800);
WIRE 16 -1 (2500 1850)(2500 1900);
WIRE 16 -1 (2500 1850)(2300 1850);
WIRE 16 -1 (2500 1900)(2500 1950);
WIRE 16 -1 (2500 1900)(2300 1900);
WIRE 16 -1 (2500 1950)(2500 2000);
WIRE 16 -1 (2500 1950)(2300 1950);
WIRE 16 -1 (2500 2000)(2500 2050);
WIRE 16 -1 (2500 2000)(2300 2000);
WIRE 16 -1 (2500 2050)(2500 2100);
WIRE 16 -1 (2500 2050)(2300 2050);
WIRE 16 -1 (2500 2100)(2500 2150);
WIRE 16 -1 (2500 2100)(2300 2100);
WIRE 16 -1 (2500 2150)(2500 2200);
WIRE 16 -1 (2500 2150)(2300 2150);
WIRE 16 -1 (2500 2200)(2500 2250);
WIRE 16 -1 (2500 2200)(2300 2200);
WIRE 16 -1 (2500 2250)(2500 2300);
WIRE 16 -1 (2500 2250)(2300 2250);
WIRE 16 -1 (2500 2300)(2500 2350);
WIRE 16 -1 (2500 2300)(2300 2300);
WIRE 16 -1 (2500 2350)(2500 2400);
WIRE 16 -1 (2500 2350)(2300 2350);
WIRE 16 -1 (2500 2400)(2500 2450);
WIRE 16 -1 (2500 2400)(2300 2400);
WIRE 16 -1 (2500 2450)(2500 2500);
WIRE 16 -1 (2500 2450)(2300 2450);
WIRE 16 -1 (2500 2500)(2500 2550);
WIRE 16 -1 (2500 2500)(2300 2500);
WIRE 16 -1 (2500 2550)(2500 2600);
WIRE 16 -1 (2500 2550)(2300 2550);
WIRE 16 -1 (2500 2600)(2500 2650);
WIRE 16 -1 (2500 2600)(2300 2600);
WIRE 16 -1 (2500 2650)(2500 2700);
WIRE 16 -1 (2500 2650)(2300 2650);
WIRE 16 -1 (2500 2700)(2500 2750);
WIRE 16 -1 (2500 2700)(2300 2700);
WIRE 16 -1 (2500 2750)(2500 2800);
WIRE 16 -1 (2500 2750)(2300 2750);
WIRE 16 -1 (2500 2800)(2500 2850);
WIRE 16 -1 (2500 2800)(2300 2800);
WIRE 16 -1 (2500 2850)(2500 2900);
WIRE 16 -1 (2500 2850)(2300 2850);
WIRE 16 -1 (2500 2900)(2500 2950);
WIRE 16 -1 (2500 2900)(2300 2900);
WIRE 16 -1 (2500 2950)(2500 3000);
WIRE 16 -1 (2500 2950)(2300 2950);
WIRE 16 -1 (2500 3000)(2500 3050);
WIRE 16 -1 (2500 3000)(2300 3000);
WIRE 16 -1 (2500 3050)(2500 3100);
WIRE 16 -1 (2500 3050)(2300 3050);
WIRE 16 -1 (2500 3100)(2500 3150);
WIRE 16 -1 (2500 3100)(2300 3100);
WIRE 16 -1 (2500 3150)(2500 3200);
WIRE 16 -1 (2500 3150)(2300 3150);
WIRE 16 -1 (2500 3200)(2500 3250);
WIRE 16 -1 (2500 3200)(2300 3200);
WIRE 16 -1 (2500 3250)(2500 3300);
WIRE 16 -1 (2500 3250)(2300 3250);
WIRE 16 -1 (2500 3300)(2500 3350);
WIRE 16 -1 (2500 3300)(2300 3300);
WIRE 16 -1 (2500 3350)(2300 3350);
WIRE 16 -1 (-5075 1575)(-5075 1475);
WIRE 16 -1 (-3025 1575)(-5075 1575);
WIRE 16 -1 (-3025 1575)(-3025 1525);
WIRE 16 -1 (-2875 1575)(-3025 1575);
WIRE 16 -1 (-3025 1525)(-3025 1475);
WIRE 16 -1 (-2875 1525)(-3025 1525);
WIRE 16 -1 (-3025 1475)(-2875 1475);
WIRE 16 -1 (-4425 975)(-4425 875);
WIRE 16 -1 (-1000 2900)(-1000 2800);
WIRE 16 -1 (-1000 2750)(-1000 2800);
WIRE 16 -1 (-1000 2800)(-800 2800);
WIRE 16 -1 (-1000 2700)(-1000 2750);
WIRE 16 -1 (-1000 2750)(-800 2750);
WIRE 16 -1 (-1000 2650)(-1000 2700);
WIRE 16 -1 (-1000 2700)(-800 2700);
WIRE 16 -1 (-1000 2600)(-1000 2650);
WIRE 16 -1 (-1000 2650)(-800 2650);
WIRE 16 -1 (-1000 2600)(-800 2600);
WIRE 16 -1 (-5075 1725)(-5075 1625);
WIRE 16 -1 (-2875 1625)(-5075 1625);
WIRE 16 -1 (400 2800)(400 2875);
WIRE 16 -1 (400 2750)(400 2800);
WIRE 16 -1 (200 2800)(400 2800);
WIRE 16 -1 (200 2750)(400 2750);
WIRE 16 -1 (1100 950)(1100 1050);
WIRE 16 -1 (1100 1050)(1100 1100);
WIRE 16 -1 (1100 1050)(1300 1050);
WIRE 16 -1 (1100 1100)(1100 1150);
WIRE 16 -1 (1100 1100)(1300 1100);
WIRE 16 -1 (1100 1150)(1100 1200);
WIRE 16 -1 (1100 1150)(1300 1150);
WIRE 16 -1 (1100 1200)(1100 1250);
WIRE 16 -1 (1100 1200)(1300 1200);
WIRE 16 -1 (1100 1250)(1100 1300);
WIRE 16 -1 (1100 1250)(1300 1250);
WIRE 16 -1 (1100 1300)(1100 1350);
WIRE 16 -1 (1100 1300)(1300 1300);
WIRE 16 -1 (1100 1350)(1100 1400);
WIRE 16 -1 (1100 1350)(1300 1350);
WIRE 16 -1 (1100 1400)(1100 1450);
WIRE 16 -1 (1100 1400)(1300 1400);
WIRE 16 -1 (1100 1450)(1100 1500);
WIRE 16 -1 (1100 1450)(1300 1450);
WIRE 16 -1 (1100 1500)(1100 1550);
WIRE 16 -1 (1100 1500)(1300 1500);
WIRE 16 -1 (1100 1550)(1100 1600);
WIRE 16 -1 (1100 1550)(1300 1550);
WIRE 16 -1 (1100 1600)(1100 1650);
WIRE 16 -1 (1100 1600)(1300 1600);
WIRE 16 -1 (1100 1650)(1100 1700);
WIRE 16 -1 (1100 1650)(1300 1650);
WIRE 16 -1 (1100 1700)(1100 1750);
WIRE 16 -1 (1100 1700)(1300 1700);
WIRE 16 -1 (1100 1750)(1100 1800);
WIRE 16 -1 (1100 1750)(1300 1750);
WIRE 16 -1 (1100 1800)(1100 1850);
WIRE 16 -1 (1100 1800)(1300 1800);
WIRE 16 -1 (1100 1850)(1100 1900);
WIRE 16 -1 (1100 1850)(1300 1850);
WIRE 16 -1 (1100 1900)(1100 1950);
WIRE 16 -1 (1100 1900)(1300 1900);
WIRE 16 -1 (1100 1950)(1100 2000);
WIRE 16 -1 (1100 1950)(1300 1950);
WIRE 16 -1 (1100 2000)(1100 2050);
WIRE 16 -1 (1100 2000)(1300 2000);
WIRE 16 -1 (1100 2050)(1100 2100);
WIRE 16 -1 (1100 2050)(1300 2050);
WIRE 16 -1 (1100 2100)(1100 2150);
WIRE 16 -1 (1100 2100)(1300 2100);
WIRE 16 -1 (1100 2150)(1100 2200);
WIRE 16 -1 (1100 2150)(1300 2150);
WIRE 16 -1 (1100 2200)(1100 2250);
WIRE 16 -1 (1100 2200)(1300 2200);
WIRE 16 -1 (1100 2250)(1100 2300);
WIRE 16 -1 (1100 2250)(1300 2250);
WIRE 16 -1 (1100 2300)(1100 2350);
WIRE 16 -1 (1100 2300)(1300 2300);
WIRE 16 -1 (1100 2350)(1100 2400);
WIRE 16 -1 (1100 2350)(1300 2350);
WIRE 16 -1 (1100 2400)(1100 2450);
WIRE 16 -1 (1100 2400)(1300 2400);
WIRE 16 -1 (1100 2450)(1100 2500);
WIRE 16 -1 (1100 2450)(1300 2450);
WIRE 16 -1 (1100 2500)(1100 2550);
WIRE 16 -1 (1100 2500)(1300 2500);
WIRE 16 -1 (1100 2550)(1100 2600);
WIRE 16 -1 (1100 2550)(1300 2550);
WIRE 16 -1 (1100 2600)(1100 2650);
WIRE 16 -1 (1100 2600)(1300 2600);
WIRE 16 -1 (1100 2650)(1100 2700);
WIRE 16 -1 (1100 2650)(1300 2650);
WIRE 16 -1 (1100 2700)(1100 2750);
WIRE 16 -1 (1100 2700)(1300 2700);
WIRE 16 -1 (1100 2750)(1100 2800);
WIRE 16 -1 (1100 2750)(1300 2750);
WIRE 16 -1 (1100 2800)(1100 2850);
WIRE 16 -1 (1100 2800)(1300 2800);
WIRE 16 -1 (1100 2850)(1100 2900);
WIRE 16 -1 (1100 2850)(1300 2850);
WIRE 16 -1 (1100 2900)(1100 2950);
WIRE 16 -1 (1100 2900)(1300 2900);
WIRE 16 -1 (1100 2950)(1100 3000);
WIRE 16 -1 (1100 2950)(1300 2950);
WIRE 16 -1 (1100 3000)(1100 3050);
WIRE 16 -1 (1100 3000)(1300 3000);
WIRE 16 -1 (1100 3050)(1100 3100);
WIRE 16 -1 (1100 3050)(1300 3050);
WIRE 16 -1 (1100 3100)(1100 3150);
WIRE 16 -1 (1100 3100)(1300 3100);
WIRE 16 -1 (1100 3150)(1100 3200);
WIRE 16 -1 (1100 3150)(1300 3150);
WIRE 16 -1 (1100 3200)(1100 3250);
WIRE 16 -1 (1100 3200)(1300 3200);
WIRE 16 -1 (1100 3250)(1100 3300);
WIRE 16 -1 (1100 3250)(1300 3250);
WIRE 16 -1 (1100 3300)(1100 3350);
WIRE 16 -1 (1100 3300)(1300 3300);
WIRE 16 -1 (1100 3350)(1300 3350);
WIRE 17 -1 (950 3325)(950 3425);
WIRE 17 -1 (950 3425)(950 3525);
WIRE 17 -1 (950 3525)(950 3625);
WIRE 17 -1 (1550 5050)(950 5050);
FORCEPROP 2 LAST SIG_NAME M_G_DQS_DN<17:0>
J 0
(975 5060);
DISPLAY 0.617021 (975 5060);
PAINT ORANGE (975 5060);
WIRE 17 -1 (950 5025)(950 5050);
WIRE 17 -1 (950 3625)(950 3725);
WIRE 17 -1 (950 3725)(950 3825);
WIRE 17 -1 (950 4925)(950 5025);
WIRE 17 -1 (950 4825)(950 4925);
WIRE 17 -1 (950 3825)(950 3925);
WIRE 17 -1 (950 3925)(950 4025);
WIRE 17 -1 (950 4725)(950 4825);
WIRE 17 -1 (950 4625)(950 4725);
WIRE 17 -1 (950 4025)(950 4125);
WIRE 17 -1 (950 4125)(950 4225);
WIRE 17 -1 (950 4525)(950 4625);
WIRE 17 -1 (950 4425)(950 4525);
WIRE 17 -1 (950 4225)(950 4325);
WIRE 17 -1 (950 4325)(950 4425);
WIRE 17 -1 (750 3375)(750 3475);
WIRE 17 -1 (750 3475)(750 3575);
WIRE 17 -1 (750 3575)(750 3675);
WIRE 17 -1 (1550 5100)(750 5100);
FORCEPROP 2 LAST SIG_NAME M_G_DQS_DP<17:0>
J 0
(975 5110);
DISPLAY 0.617021 (975 5110);
PAINT ORANGE (975 5110);
WIRE 17 -1 (750 5075)(750 5100);
WIRE 17 -1 (750 3675)(750 3775);
WIRE 17 -1 (750 3775)(750 3875);
WIRE 17 -1 (750 4975)(750 5075);
WIRE 17 -1 (750 4875)(750 4975);
WIRE 17 -1 (750 3875)(750 3975);
WIRE 17 -1 (750 3975)(750 4075);
WIRE 17 -1 (750 4775)(750 4875);
WIRE 17 -1 (750 4675)(750 4775);
WIRE 17 -1 (750 4075)(750 4175);
WIRE 17 -1 (750 4175)(750 4275);
WIRE 17 -1 (750 4575)(750 4675);
WIRE 17 -1 (750 4475)(750 4575);
WIRE 17 -1 (750 4275)(750 4375);
WIRE 17 -1 (750 4375)(750 4475);
WIRE 17 -1 (-1575 1300)(-1575 1350);
WIRE 17 -1 (-1575 1350)(-1575 1400);
WIRE 17 -1 (-1575 1400)(-1575 1450);
WIRE 17 -1 (-1575 1450)(-1575 1500);
WIRE 17 -1 (-1575 1500)(-1575 1550);
WIRE 17 -1 (-1575 1550)(-1575 1600);
WIRE 17 -1 (-1575 1600)(-1575 1650);
WIRE 17 -1 (-1575 1650)(-1575 1700);
WIRE 17 -1 (-1575 1700)(-1575 1750);
WIRE 17 -1 (-1575 1750)(-1575 1800);
WIRE 17 -1 (-1575 1800)(-1575 1850);
WIRE 17 -1 (-1575 1850)(-1575 1900);
WIRE 17 -1 (-1575 1900)(-1575 1950);
WIRE 17 -1 (-1575 1950)(-1575 2000);
WIRE 17 -1 (-1575 2000)(-1575 2050);
WIRE 17 -1 (-1575 2050)(-1575 2100);
WIRE 17 -1 (-1575 2100)(-1575 2150);
WIRE 17 -1 (-1575 2150)(-1575 2200);
WIRE 17 -1 (-1575 2200)(-1575 2250);
WIRE 17 -1 (-1575 2250)(-1575 2300);
WIRE 17 -1 (-1575 2300)(-1575 2350);
WIRE 17 -1 (-1575 2350)(-1575 2400);
WIRE 17 -1 (-1575 2400)(-1575 2450);
WIRE 17 -1 (-1575 2450)(-1575 2500);
WIRE 17 -1 (-1575 2500)(-1575 2550);
WIRE 17 -1 (-1575 2550)(-1575 2600);
WIRE 17 -1 (-1575 2600)(-1575 2650);
WIRE 17 -1 (-1575 2650)(-1575 2700);
WIRE 17 -1 (-1575 2700)(-1575 2750);
WIRE 17 -1 (-1575 2750)(-1575 2800);
WIRE 17 -1 (-1575 2800)(-1575 2850);
WIRE 17 -1 (-1575 2850)(-1575 2900);
WIRE 17 -1 (-1575 2900)(-1575 2950);
WIRE 17 -1 (-1575 2950)(-1575 3000);
WIRE 17 -1 (-1575 3000)(-1575 3050);
WIRE 17 -1 (-1575 3050)(-1575 3100);
WIRE 17 -1 (-1575 3100)(-1575 3150);
WIRE 17 -1 (-1575 3150)(-1575 3200);
WIRE 17 -1 (-1575 3200)(-1575 3250);
WIRE 17 -1 (-1575 3250)(-1575 3300);
WIRE 17 -1 (-1575 3300)(-1575 3350);
WIRE 17 -1 (-1575 3350)(-1575 3400);
WIRE 17 -1 (-1575 3400)(-1575 3450);
WIRE 17 -1 (-1575 3450)(-1575 3500);
WIRE 17 -1 (-1575 3500)(-1575 3550);
WIRE 17 -1 (-1575 3550)(-1575 3600);
WIRE 17 -1 (-1575 3600)(-1575 3650);
WIRE 17 -1 (-1575 3650)(-1575 3700);
WIRE 17 -1 (-1575 3700)(-1575 3750);
WIRE 17 -1 (-1575 3750)(-1575 3800);
WIRE 17 -1 (-1125 4475)(-1575 4475);
FORCEPROP 2 LAST SIG_NAME M_G_DQ<63:0>
J 0
(-1535 4485);
DISPLAY 0.617021 (-1535 4485);
PAINT ORANGE (-1535 4485);
WIRE 17 -1 (-1575 3800)(-1575 3850);
WIRE 17 -1 (-1575 3850)(-1575 3900);
WIRE 17 -1 (-1575 4475)(-1575 4450);
WIRE 17 -1 (-1575 4400)(-1575 4450);
WIRE 17 -1 (-1575 3900)(-1575 3950);
WIRE 17 -1 (-1575 3950)(-1575 4000);
WIRE 17 -1 (-1575 4350)(-1575 4400);
WIRE 17 -1 (-1575 4300)(-1575 4350);
WIRE 17 -1 (-1575 4000)(-1575 4050);
WIRE 17 -1 (-1575 4050)(-1575 4100);
WIRE 17 -1 (-1575 4250)(-1575 4300);
WIRE 17 -1 (-1575 4200)(-1575 4250);
WIRE 17 -1 (-1575 4100)(-1575 4150);
WIRE 17 -1 (-1575 4150)(-1575 4200);
WIRE 17 -1 (-3175 3600)(-3175 3650);
WIRE 17 -1 (-3175 3650)(-3175 3700);
WIRE 17 -1 (-3175 3700)(-3175 3750);
WIRE 17 -1 (-3175 3750)(-3175 3800);
WIRE 17 -1 (-3175 3800)(-3175 3850);
WIRE 17 -1 (-3175 3850)(-3175 3900);
WIRE 17 -1 (-3175 3900)(-3175 3950);
WIRE 17 -1 (-3725 4475)(-3175 4475);
FORCEPROP 2 LAST SIG_NAME M_G_MA<17:0>
J 0
(-3700 4485);
DISPLAY 0.617021 (-3700 4485);
PAINT ORANGE (-3700 4485);
WIRE 17 -1 (-3175 4450)(-3175 4475);
WIRE 17 -1 (-3175 3950)(-3175 4000);
WIRE 17 -1 (-3175 4000)(-3175 4050);
WIRE 17 -1 (-3175 4400)(-3175 4450);
WIRE 17 -1 (-3175 4350)(-3175 4400);
WIRE 17 -1 (-3175 4050)(-3175 4100);
WIRE 17 -1 (-3175 4100)(-3175 4150);
WIRE 17 -1 (-3175 4300)(-3175 4350);
WIRE 17 -1 (-3175 4250)(-3175 4300);
WIRE 17 -1 (-3175 4150)(-3175 4200);
WIRE 17 -1 (-3175 4200)(-3175 4250);
WIRE 17 -1 (-3375 3200)(-3375 3100);
WIRE 17 -1 (-3375 3250)(-3725 3250);
FORCEPROP 2 LAST SIG_NAME M_G_CLK_DN<3:0>
J 0
(-3725 3260);
DISPLAY 0.617021 (-3725 3260);
PAINT ORANGE (-3725 3260);
WIRE 17 -1 (-3375 3250)(-3375 3200);
WIRE 17 -1 (-3175 3300)(-3725 3300);
FORCEPROP 2 LAST SIG_NAME M_G_CLK_DP<3:0>
J 0
(-3725 3310);
DISPLAY 0.617021 (-3725 3310);
PAINT ORANGE (-3725 3310);
WIRE 17 -1 (-3175 3300)(-3175 3250);
WIRE 17 -1 (-3175 3150)(-3175 3250);
WIRE 17 -1 (-3175 3450)(-3175 3500);
WIRE 17 -1 (-3175 3550)(-3725 3550);
FORCEPROP 2 LAST SIG_NAME M_G_BA<1:0>
J 0
(-3700 3560);
DISPLAY 0.617021 (-3700 3560);
PAINT ORANGE (-3700 3560);
WIRE 17 -1 (-3175 3550)(-3175 3500);
WIRE 17 -1 (-3175 2800)(-3175 2850);
WIRE 17 -1 (-3175 2850)(-3175 2900);
WIRE 17 -1 (-3175 2900)(-3175 2950);
WIRE 17 -1 (-3175 2975)(-3725 2975);
FORCEPROP 2 LAST SIG_NAME M_G_CS_N<7:0>
J 0
(-3700 2985);
DISPLAY 0.617021 (-3700 2985);
PAINT ORANGE (-3700 2985);
WIRE 17 -1 (-3175 2975)(-3175 2950);
WIRE 17 -1 (-3175 2050)(-3175 2100);
WIRE 17 -1 (-3175 2100)(-3175 2150);
WIRE 17 -1 (-3175 2150)(-3175 2200);
WIRE 17 -1 (-3175 2200)(-3175 2250);
WIRE 17 -1 (-3175 2250)(-3175 2300);
WIRE 17 -1 (-3175 2425)(-3725 2425);
FORCEPROP 2 LAST SIG_NAME M_G_ECC<7:0>
J 0
(-3700 2435);
DISPLAY 0.617021 (-3700 2435);
PAINT ORANGE (-3700 2435);
WIRE 17 -1 (-3175 2425)(-3175 2400);
WIRE 17 -1 (-3175 2300)(-3175 2350);
WIRE 17 -1 (-3175 2350)(-3175 2400);
WIRE 17 -1 (-3175 2650)(-3175 2700);
WIRE 17 -1 (-3175 2725)(-3725 2725);
FORCEPROP 2 LAST SIG_NAME M_G_CKE<3:0>
J 0
(-3700 2735);
DISPLAY 0.617021 (-3700 2735);
PAINT ORANGE (-3700 2735);
WIRE 17 -1 (-3175 2725)(-3175 2700);
WIRE 17 -1 (-3175 3425)(-3725 3425);
FORCEPROP 2 LAST SIG_NAME M_G_BG<1:0>
J 0
(-3700 3435);
DISPLAY 0.617021 (-3700 3435);
PAINT ORANGE (-3700 3435);
WIRE 17 -1 (-3175 3425)(-3175 3400);
WIRE 17 -1 (-3175 3350)(-3175 3400);
WIRE 17 -1 (-3175 2575)(-3725 2575);
FORCEPROP 2 LAST SIG_NAME M_G_ODT<3:0>
J 0
(-3700 2585);
DISPLAY 0.617021 (-3700 2585);
PAINT ORANGE (-3700 2585);
WIRE 17 -1 (-3175 2575)(-3175 2550);
WIRE 17 -1 (-3175 2500)(-3175 2550);
WIRE 16 -1 (-2875 3875)(-3075 3875);
WIRE 16 -1 (850 4000)(450 4000);
WIRE 16 -1 (-1675 2275)(-1875 2275);
WIRE 16 -1 (-1675 4225)(-1875 4225);
WIRE 16 -1 (-1675 1425)(-1875 1425);
WIRE 16 -1 (-3725 1375)(-2875 1375);
FORCEPROP 2 LAST SIG_NAME SMB_DDR_GHJ_VPP_SCL
J 0
(-3685 1385);
DISPLAY 0.617021 (-3685 1385);
PAINT ORANGE (-3685 1385);
WIRE 16 -1 (-1675 4275)(-1875 4275);
WIRE 16 -1 (850 3900)(450 3900);
WIRE 16 -1 (-4525 1275)(-4425 1275);
WIRE 16 -1 (-4425 1275)(-4425 1175);
WIRE 16 -1 (-2875 1275)(-4425 1275);
FORCEPROP 2 LAST SIG_NAME M_G_VREF
J 0
(-4175 1285);
DISPLAY 0.617021 (-4175 1285);
PAINT ORANGE (-4175 1285);
WIRE 16 -1 (-3725 1125)(-2875 1125);
FORCEPROP 2 LAST SIG_NAME TP_CH_G_DIMM_G0_RFU_1
J 0
(-3675 1135);
DISPLAY 0.617021 (-3675 1135);
PAINT ORANGE (-3675 1135);
FORCEPROP 2 LASTPROP $XRERR UNIQUE?
J 0
(-3965 1125);
DISPLAY 0.638298 (-3965 1125);
PAINT MONO (-3965 1125);
DISPLAY INVISIBLE (-3965 1125);
WIRE 16 -1 (-3725 1175)(-2875 1175);
FORCEPROP 2 LAST SIG_NAME TP_CH_G_DIMM_G0_RFU_2
J 0
(-3675 1185);
DISPLAY 0.617021 (-3675 1185);
PAINT ORANGE (-3675 1185);
FORCEPROP 2 LASTPROP $XRERR UNIQUE?
J 0
(-3965 1175);
DISPLAY 0.638298 (-3965 1175);
PAINT MONO (-3965 1175);
DISPLAY INVISIBLE (-3965 1175);
WIRE 16 -1 (-2875 2025)(-3075 2025);
WIRE 16 -1 (-3725 1075)(-2875 1075);
FORCEPROP 2 LAST SIG_NAME TP_CH_G_DIMM_G0_RFU_0
J 0
(-3675 1085);
DISPLAY 0.617021 (-3675 1085);
PAINT ORANGE (-3675 1085);
FORCEPROP 2 LASTPROP $XRERR UNIQUE?
J 0
(-3965 1075);
DISPLAY 0.638298 (-3965 1075);
PAINT MONO (-3965 1075);
DISPLAY INVISIBLE (-3965 1075);
WIRE 16 -1 (-2875 1725)(-3875 1725);
FORCEPROP 2 LAST SIG_NAME M_G_ACT_N
J 0
(-3825 1735);
DISPLAY 0.617021 (-3825 1735);
PAINT ORANGE (-3825 1735);
WIRE 16 -1 (-2875 1775)(-3900 1775);
FORCEPROP 2 LAST SIG_NAME M_G_ALERT_N
J 0
(-3850 1785);
DISPLAY 0.617021 (-3850 1785);
PAINT ORANGE (-3850 1785);
WIRE 16 -1 (-3725 1425)(-2875 1425);
WIRE 16 -1 (-3725 975)(-2875 975);
FORCEPROP 2 LAST SIG_NAME FM_ADR_COMPLETE_GHJ_N
J 0
(-3675 985);
DISPLAY 0.617021 (-3675 985);
PAINT ORANGE (-3675 985);
WIRE 16 -1 (-3325 1825)(-2875 1825);
WIRE 16 -1 (-3325 1825)(-3325 2075);
WIRE 16 -1 (-3325 2075)(-4050 2075);
FORCEPROP 2 LAST SIG_NAME FM_DIMM_EVENT_COD_N
J 0
(-4041 2090);
DISPLAY 0.617021 (-4041 2090);
PAINT ORANGE (-4041 2090);
WIRE 16 -1 (-2875 1925)(-3225 1925);
WIRE 16 -1 (-3225 1925)(-3225 2375);
WIRE 16 -1 (-3225 2375)(-3725 2375);
FORCEPROP 2 LAST SIG_NAME M_G_PAR
J 0
(-3700 2385);
DISPLAY 0.617021 (-3700 2385);
PAINT ORANGE (-3700 2385);
WIRE 16 -1 (-2875 1875)(-3275 1875);
WIRE 16 -1 (-3275 1875)(-3275 2325);
WIRE 16 -1 (-3275 2325)(-3725 2325);
FORCEPROP 2 LAST SIG_NAME M_GHJ_RST_N
J 0
(-3700 2335);
DISPLAY 0.617021 (-3700 2335);
PAINT ORANGE (-3700 2335);
WIRE 16 -1 (-2875 2775)(-3075 2775);
WIRE 16 -1 (-2875 2625)(-3075 2625);
WIRE 16 -1 (-2875 2525)(-3075 2525);
WIRE 16 -1 (-2875 2475)(-3075 2475);
WIRE 16 -1 (-2875 2375)(-3075 2375);
WIRE 16 -1 (-2875 4075)(-3075 4075);
WIRE 16 -1 (-2875 3675)(-3075 3675);
WIRE 16 -1 (-2875 3425)(-3075 3425);
WIRE 16 -1 (-2875 3375)(-3075 3375);
WIRE 16 -1 (-2875 3325)(-3075 3325);
WIRE 16 -1 (-2875 3225)(-3075 3225);
WIRE 16 -1 (-2875 2675)(-3075 2675);
WIRE 16 -1 (-2875 2075)(-3075 2075);
WIRE 16 -1 (-2875 2125)(-3075 2125);
WIRE 16 -1 (-2875 2175)(-3075 2175);
WIRE 16 -1 (-2875 2225)(-3075 2225);
WIRE 16 -1 (-2875 2275)(-3075 2275);
WIRE 16 -1 (-2875 2325)(-3075 2325);
WIRE 16 -1 (-2875 4025)(-3075 4025);
WIRE 16 -1 (-2875 3975)(-3075 3975);
WIRE 16 -1 (-2875 3925)(-3075 3925);
WIRE 16 -1 (-2875 3825)(-3075 3825);
WIRE 16 -1 (-2875 3775)(-3075 3775);
WIRE 16 -1 (-2875 3725)(-3075 3725);
WIRE 16 -1 (-2875 3625)(-3075 3625);
WIRE 16 -1 (-2875 3575)(-3075 3575);
WIRE 16 -1 (-2875 2825)(-3075 2825);
WIRE 16 -1 (-2875 2875)(-3075 2875);
WIRE 16 -1 (-2875 2925)(-3075 2925);
WIRE 16 -1 (-2875 3475)(-3075 3475);
WIRE 16 -1 (-2875 3075)(-3275 3075);
WIRE 16 -1 (-2875 3125)(-3075 3125);
WIRE 16 -1 (-2875 3175)(-3275 3175);
WIRE 16 -1 (-3025 3025)(-3725 3025);
FORCEPROP 2 LAST SIG_NAME M_G_C<2>
J 0
(-3700 3035);
DISPLAY 0.617021 (-3700 3035);
PAINT ORANGE (-3700 3035);
WIRE 16 -1 (-3025 3025)(-3025 2975);
WIRE 16 -1 (-3025 2975)(-2875 2975);
WIRE 16 -1 (-1675 1475)(-1875 1475);
WIRE 16 -1 (-1675 1375)(-1875 1375);
WIRE 16 -1 (-1675 1275)(-1875 1275);
WIRE 16 -1 (-1675 1325)(-1875 1325);
WIRE 16 -1 (-1675 1525)(-1875 1525);
WIRE 16 -1 (-1675 2025)(-1875 2025);
WIRE 16 -1 (-1675 1575)(-1875 1575);
WIRE 16 -1 (-1675 1675)(-1875 1675);
WIRE 16 -1 (-1675 1725)(-1875 1725);
WIRE 16 -1 (-1675 1775)(-1875 1775);
WIRE 16 -1 (-1675 1825)(-1875 1825);
WIRE 16 -1 (-1675 1875)(-1875 1875);
WIRE 16 -1 (-1675 1925)(-1875 1925);
WIRE 16 -1 (-1675 1975)(-1875 1975);
WIRE 16 -1 (-1675 1625)(-1875 1625);
WIRE 16 -1 (-1675 2175)(-1875 2175);
WIRE 16 -1 (-1675 2225)(-1875 2225);
WIRE 16 -1 (-1675 2325)(-1875 2325);
WIRE 16 -1 (-1675 2375)(-1875 2375);
WIRE 16 -1 (-1675 2425)(-1875 2425);
WIRE 16 -1 (-1675 2475)(-1875 2475);
WIRE 16 -1 (-1675 2525)(-1875 2525);
WIRE 16 -1 (-1675 2075)(-1875 2075);
WIRE 16 -1 (-1675 2125)(-1875 2125);
WIRE 16 -1 (-1675 2575)(-1875 2575);
WIRE 16 -1 (-1675 3025)(-1875 3025);
WIRE 16 -1 (-1675 2775)(-1875 2775);
WIRE 16 -1 (-1675 2825)(-1875 2825);
WIRE 16 -1 (-1675 2875)(-1875 2875);
WIRE 16 -1 (-1675 2925)(-1875 2925);
WIRE 16 -1 (-1675 2975)(-1875 2975);
WIRE 16 -1 (-1675 2675)(-1875 2675);
WIRE 16 -1 (-1675 2725)(-1875 2725);
WIRE 16 -1 (-1675 2625)(-1875 2625);
WIRE 16 -1 (-1675 3175)(-1875 3175);
WIRE 16 -1 (-1675 3075)(-1875 3075);
WIRE 16 -1 (-1675 3125)(-1875 3125);
WIRE 16 -1 (-1675 3275)(-1875 3275);
WIRE 16 -1 (-1675 3375)(-1875 3375);
WIRE 16 -1 (-1675 3525)(-1875 3525);
WIRE 16 -1 (-1675 3575)(-1875 3575);
WIRE 16 -1 (-1675 3475)(-1875 3475);
WIRE 16 -1 (-1675 3425)(-1875 3425);
WIRE 16 -1 (-1675 3325)(-1875 3325);
WIRE 16 -1 (-1675 3225)(-1875 3225);
WIRE 16 -1 (-1675 3625)(-1875 3625);
WIRE 16 -1 (-1675 3825)(-1875 3825);
WIRE 16 -1 (-1675 3875)(-1875 3875);
WIRE 16 -1 (-1675 3925)(-1875 3925);
WIRE 16 -1 (-1675 3975)(-1875 3975);
WIRE 16 -1 (-1675 4025)(-1875 4025);
WIRE 16 -1 (-1675 4075)(-1875 4075);
WIRE 16 -1 (-1675 3775)(-1875 3775);
WIRE 16 -1 (-1675 3725)(-1875 3725);
WIRE 16 -1 (-1675 3675)(-1875 3675);
WIRE 16 -1 (-2875 4375)(-3075 4375);
WIRE 16 -1 (-2875 4325)(-3075 4325);
WIRE 16 -1 (-2875 4275)(-3075 4275);
WIRE 16 -1 (-2875 4125)(-3075 4125);
WIRE 16 -1 (-2875 4425)(-3075 4425);
WIRE 16 -1 (-2875 4225)(-3075 4225);
WIRE 16 -1 (-2875 4175)(-3075 4175);
WIRE 16 -1 (-1675 4425)(-1875 4425);
WIRE 16 -1 (-1675 4375)(-1875 4375);
WIRE 16 -1 (-1675 4325)(-1875 4325);
WIRE 16 -1 (-1675 4175)(-1875 4175);
WIRE 16 -1 (-1675 4125)(-1875 4125);
WIRE 16 -1 (650 4050)(450 4050);
WIRE 16 -1 (650 3950)(450 3950);
WIRE 16 -1 (650 3850)(450 3850);
WIRE 16 -1 (850 3800)(450 3800);
WIRE 16 -1 (650 3750)(450 3750);
WIRE 16 -1 (850 3700)(450 3700);
WIRE 16 -1 (650 3650)(450 3650);
WIRE 16 -1 (850 3600)(450 3600);
WIRE 16 -1 (650 3550)(450 3550);
WIRE 16 -1 (850 3500)(450 3500);
WIRE 16 -1 (650 3450)(450 3450);
WIRE 16 -1 (850 3400)(450 3400);
WIRE 16 -1 (650 3350)(450 3350);
WIRE 16 -1 (850 3300)(450 3300);
WIRE 16 -1 (650 5050)(450 5050);
WIRE 16 -1 (650 4250)(450 4250);
WIRE 16 -1 (850 4200)(450 4200);
WIRE 16 -1 (650 4150)(450 4150);
WIRE 16 -1 (850 4100)(450 4100);
WIRE 16 -1 (850 5000)(450 5000);
WIRE 16 -1 (650 4950)(450 4950);
WIRE 16 -1 (850 4900)(450 4900);
WIRE 16 -1 (650 4850)(450 4850);
WIRE 16 -1 (850 4800)(450 4800);
WIRE 16 -1 (650 4750)(450 4750);
WIRE 16 -1 (850 4700)(450 4700);
WIRE 16 -1 (650 4650)(450 4650);
WIRE 16 -1 (850 4600)(450 4600);
WIRE 16 -1 (650 4550)(450 4550);
WIRE 16 -1 (850 4500)(450 4500);
WIRE 16 -1 (650 4450)(450 4450);
WIRE 16 -1 (850 4400)(450 4400);
WIRE 16 -1 (650 4350)(450 4350);
WIRE 16 -1 (850 4300)(450 4300);
DOT 1 (-1000 2500);
DOT 1 (-1000 2250);
DOT 1 (-1000 2200);
DOT 1 (1100 3250);
DOT 1 (2500 2700);
DOT 1 (1100 3200);
DOT 1 (1100 1050);
DOT 1 (1100 1100);
DOT 1 (1100 1150);
DOT 1 (1100 1250);
DOT 1 (1100 1200);
DOT 1 (1100 1300);
DOT 1 (1100 1350);
DOT 1 (1100 1500);
DOT 1 (1100 1600);
DOT 1 (1100 1550);
DOT 1 (1100 1650);
DOT 1 (1100 1750);
DOT 1 (1100 1700);
DOT 1 (1100 1800);
DOT 1 (1100 1850);
DOT 1 (1100 1900);
DOT 1 (1100 1950);
DOT 1 (1100 2000);
DOT 1 (1100 2050);
DOT 1 (1100 2100);
DOT 1 (1100 2150);
DOT 1 (1100 2200);
DOT 1 (1100 2250);
DOT 1 (1100 2300);
DOT 1 (1100 2400);
DOT 1 (1100 2350);
DOT 1 (1100 2450);
DOT 1 (1100 2500);
DOT 1 (1100 2550);
DOT 1 (1100 2650);
DOT 1 (1100 2600);
DOT 1 (1100 2700);
DOT 1 (1100 2800);
DOT 1 (1100 2900);
DOT 1 (1100 2850);
DOT 1 (1100 2950);
DOT 1 (1100 3000);
DOT 1 (1100 3050);
DOT 1 (1100 3150);
DOT 1 (1100 3100);
DOT 1 (1100 3300);
DOT 1 (2500 1050);
DOT 1 (2500 1100);
DOT 1 (2500 1150);
DOT 1 (2500 1200);
DOT 1 (2500 1250);
DOT 1 (2500 1300);
DOT 1 (2500 1350);
DOT 1 (2500 1400);
DOT 1 (2500 1450);
DOT 1 (2500 1500);
DOT 1 (2500 1550);
DOT 1 (2500 1600);
DOT 1 (2500 1650);
DOT 1 (2500 1700);
DOT 1 (2500 1750);
DOT 1 (2500 1800);
DOT 1 (2500 1850);
DOT 1 (2500 1900);
DOT 1 (2500 1950);
DOT 1 (2500 2000);
DOT 1 (2500 2050);
DOT 1 (2500 2100);
DOT 1 (2500 2150);
DOT 1 (2500 2200);
DOT 1 (2500 2250);
DOT 1 (2500 2300);
DOT 1 (2500 2350);
DOT 1 (2500 2400);
DOT 1 (2500 2450);
DOT 1 (2500 2500);
DOT 1 (2500 2550);
DOT 1 (2500 2600);
DOT 1 (2500 2650);
DOT 1 (2500 2750);
DOT 1 (2500 2800);
DOT 1 (2500 2850);
DOT 1 (2500 2900);
DOT 1 (2500 2950);
DOT 1 (2500 3000);
DOT 1 (2500 3050);
DOT 1 (2500 3100);
DOT 1 (2500 3150);
DOT 1 (2500 3200);
DOT 1 (2500 3250);
DOT 1 (2500 3300);
DOT 1 (-1000 2750);
DOT 1 (-1000 2700);
DOT 1 (-1000 2300);
DOT 1 (-1000 2350);
DOT 1 (-1000 2150);
DOT 1 (-1000 2050);
DOT 1 (-1000 2100);
DOT 1 (-1000 1950);
DOT 1 (-1000 2000);
DOT 1 (-1000 1900);
DOT 1 (-1000 1850);
DOT 1 (-1000 1800);
DOT 1 (-1000 1750);
DOT 1 (-1000 1700);
DOT 1 (-1000 1650);
DOT 1 (-1000 1450);
DOT 1 (-1000 1500);
DOT 1 (-1000 1350);
DOT 1 (-1000 1150);
DOT 1 (-1000 1250);
DOT 1 (-1000 1200);
DOT 1 (-1000 2650);
DOT 1 (-3025 1525);
DOT 1 (-4425 1275);
DOT 1 (-1000 2800);
DOT 1 (-3025 1575);
DOT 1 (400 2800);
DOT 1 (-1000 1300);
DOT 1 (1100 1450);
DOT 1 (1100 1400);
DOT 1 (-1000 1600);
DOT 1 (-1000 1550);
DOT 1 (-1000 1400);
DOT 1 (1100 2750);
FORCENOTE
PVDDQ (SINGLE SIDE) CAP: 10UF X1, 22UF X50
(-3200 5100) 0;
DISPLAY LEFT (-3200 5100);
DISPLAY 1.021277 (-3200 5100);
PAINT PURPLE (-3200 5100);
FORCENOTE
PVDDQ (DOUBLE SIDE) CAP: 100UF X8, 47UF X41
(-3200 5050) 0;
DISPLAY LEFT (-3200 5050);
DISPLAY 1.021277 (-3200 5050);
PAINT PURPLE (-3200 5050);
FORCENOTE
PVTT CAP: 100UF X2, 47UF X1
(-3200 5150) 0;
DISPLAY LEFT (-3200 5150);
DISPLAY 1.021277 (-3200 5150);
PAINT PURPLE (-3200 5150);
FORCENOTE
PLACE CAP NEAR DIMM CONNECTOR
(-5288 702) 0;
DISPLAY LEFT (-5288 702);
DISPLAY 1.957447 (-5288 702);
PAINT PURPLE (-5288 702);
FORCENOTE
SMBUS ADDR: 0XA0
(-5300 600) 0;
DISPLAY LEFT (-5300 600);
DISPLAY 1.957447 (-5300 600);
PAINT PURPLE (-5300 600);
FORCENOTE
CAP BETWEEN DIMM
(-3200 5275) 0;
DISPLAY LEFT (-3200 5275);
DISPLAY 1.276596 (-3200 5275);
PAINT PURPLE (-3200 5275);
FORCENOTE
PVPP CAP: 10UF X12
(-3200 5200) 0;
DISPLAY LEFT (-3200 5200);
DISPLAY 1.021277 (-3200 5200);
PAINT PURPLE (-3200 5200);
QUIT
